FILE_TYPE = MACRO_DRAWING;
SET COLOR_WIRE YELLOW;
SET COLOR_PROP MONO;
SET COLOR_DOT WHITE;
SET COLOR_ARC YELLOW;
SET COLOR_BODY GREEN;
SET COLOR_NOTE MONO;
SET PROP_DISPLAY VALUE;
SET PAGE_NUMBER P210;
FORCEADD OFFPAGE..4
(-1700 4625);
FORCEPROP 2 LAST $XR0 206 
J 0
(-1514 4625);
DISPLAY 0.638298 (-1514 4625);
PAINT MONO (-1514 4625);
FORCEPROP 2 LAST BOM_COST PROC_VRD_VCCIN_CPU0
J 0
(-1500 4675);
DISPLAY 1.446809 (-1500 4675);
PAINT MONO (-1500 4675);
DISPLAY INVISIBLE (-1500 4675);
FORCEPROP 2 LAST PATH I1
J 0
(-1345 4675);
DISPLAY 1.021277 (-1345 4675);
PAINT ORANGE (-1345 4675);
DISPLAY INVISIBLE (-1345 4675);
FORCEPROP 1 LAST OFFPAGE TRUE
J 0
(-1375 4500);
DISPLAY 0.872340 (-1375 4500);
PAINT GREEN (-1375 4500);
DISPLAY INVISIBLE (-1375 4500);
FORCEPROP 2 LAST CDS_LIB mstr_standard
J 0
(-1700 4625);
PAINT ORANGE (-1700 4625);
DISPLAY INVISIBLE (-1700 4625);
FORCEPROP 1 LAST COMMENT_BODY TRUE
J 0
(-1725 4525);
DISPLAY 0.872340 (-1725 4525);
PAINT GREEN (-1725 4525);
DISPLAY INVISIBLE (-1725 4525);
FORCEPROP 2 LAST ROOM PVSA_CPU1_PWR_VR
J 0
(-2100 4700);
DISPLAY 1.936170 (-2100 4700);
PAINT ORANGE (-2100 4700);
DISPLAY INVISIBLE (-2100 4700);
FORCEADD INDUCTOR..1
(-1900 3300);
FORCEPROP 1 LAST PART_NUMBER D92183-036
J 0
(-2000 3400);
DISPLAY 0.617021 (-2000 3400);
PAINT BLUE (-2000 3400);
FORCEPROP 1 LAST MATERIAL IND
J 0
(-1885 3215);
DISPLAY 0.617021 (-1885 3215);
PAINT SKYBLUE (-1885 3215);
FORCEPROP 1 LAST PACK_TYPE SM
J 0
(-1810 3215);
DISPLAY 0.617021 (-1810 3215);
PAINT SKYBLUE (-1810 3215);
FORCEPROP 1 LASTPIN (-2000 3300) $PN 1
J 0
(-2000 3310);
DISPLAY 0.617021 (-2000 3310);
PAINT WHITE (-2000 3310);
FORCEPROP 1 LASTPIN (-1800 3300) $PN 2
J 2
(-1790 3310);
DISPLAY 0.617021 (-1790 3310);
PAINT WHITE (-1790 3310);
FORCEPROP 1 LAST LOCATION L1C1
J 0
(-2000 3350);
DISPLAY 0.617021 (-2000 3350);
PAINT AQUA (-2000 3350);
FORCEPROP 1 LAST VALUE 0.3UH
J 2
(-1905 3215);
DISPLAY 0.617021 (-1905 3215);
PAINT SKYBLUE (-1905 3215);
FORCEPROP 2 LAST CDS_LIB mstr_discrete
J 0
(-1900 3300);
PAINT ORANGE (-1900 3300);
DISPLAY INVISIBLE (-1900 3300);
FORCEPROP 2 LAST ROOM PVSA_CPU1_PWR_VR
J 0
(-2000 3400);
DISPLAY 1.361702 (-2000 3400);
PAINT ORANGE (-2000 3400);
DISPLAY INVISIBLE (-2000 3400);
FORCEPROP 1 LAST PATH I10
J 0
(-2000 3450);
DISPLAY 0.978723 (-2000 3450);
PAINT ORANGE (-2000 3450);
DISPLAY INVISIBLE (-2000 3450);
FORCEPROP 2 LAST CDS_LOCATION L1C1
J 0
(-2000 3350);
DISPLAY 0.617021 (-2000 3350);
PAINT AQUA (-2000 3350);
DISPLAY INVISIBLE (-2000 3350);
FORCEPROP 2 LAST SEC 1
J 0
(-2000 3500);
DISPLAY 0.680851 (-2000 3500);
PAINT MONO (-2000 3500);
DISPLAY INVISIBLE (-2000 3500);
FORCEPROP 2 LAST SEC_TYPE SM
J 0
(-2000 3500);
DISPLAY 1.021277 (-2000 3500);
PAINT ORANGE (-2000 3500);
DISPLAY INVISIBLE (-2000 3500);
FORCEADD CAPP..1
(-1325 1375);
FORCEPROP 1 LAST PART_NUMBER 699013-049
J 0
(-1275 1175);
DISPLAY 0.617021 (-1275 1175);
PAINT BLUE (-1275 1175);
FORCEPROP 1 LAST LOCATION C9N11
J 0
(-1275 1475);
DISPLAY 0.617021 (-1275 1475);
PAINT AQUA (-1275 1475);
FORCEPROP 1 LAST VALUE 470UF
J 0
(-1275 1425);
DISPLAY 0.617021 (-1275 1425);
PAINT SKYBLUE (-1275 1425);
FORCEPROP 1 LAST TOLERANCE 20%
J 0
(-1275 1375);
DISPLAY 0.617021 (-1275 1375);
PAINT SKYBLUE (-1275 1375);
FORCEPROP 1 LAST PACK_TYPE 3018
J 0
(-1275 1225);
DISPLAY 0.617021 (-1275 1225);
PAINT SKYBLUE (-1275 1225);
FORCEPROP 1 LAST MATERIAL ALUM
J 0
(-1275 1275);
DISPLAY 0.617021 (-1275 1275);
PAINT SKYBLUE (-1275 1275);
FORCEPROP 1 LASTPIN (-1325 1475) $PN 1
J 0
(-1315 1460);
DISPLAY 0.617021 (-1315 1460);
PAINT ORANGE (-1315 1460);
FORCEPROP 1 LASTPIN (-1325 1275) $PN 2
J 0
(-1315 1260);
DISPLAY 0.617021 (-1315 1260);
PAINT ORANGE (-1315 1260);
FORCEPROP 2 LAST SEC 1
J 0
(-1275 1575);
PAINT MONO (-1275 1575);
DISPLAY INVISIBLE (-1275 1575);
FORCEPROP 2 LAST SEC_TYPE 3018
J 0
(-1270 1595);
DISPLAY 1.021277 (-1270 1595);
PAINT ORANGE (-1270 1595);
DISPLAY INVISIBLE (-1270 1595);
FORCEPROP 2 LAST BOM_COST PROC_VRD_VCCIN_CPU0
J 0
(-1275 1525);
PAINT MONO (-1275 1525);
DISPLAY INVISIBLE (-1275 1525);
FORCEPROP 1 LAST PATH I12
J 0
(-1275 1525);
DISPLAY 0.978723 (-1275 1525);
PAINT ORANGE (-1275 1525);
DISPLAY INVISIBLE (-1275 1525);
FORCEPROP 2 LAST ROOM PVSA_CPU1_DECAP_VR
J 0
(-1275 1500);
PAINT MONO (-1275 1500);
DISPLAY INVISIBLE (-1275 1500);
FORCEPROP 1 LAST VOLTAGE 2.5V
J 0
(-1275 1325);
PAINT SKYBLUE (-1275 1325);
DISPLAY INVISIBLE (-1275 1325);
FORCEPROP 2 LAST CDS_LOCATION C9N11
J 0
(-1275 1475);
DISPLAY 0.617021 (-1275 1475);
PAINT AQUA (-1275 1475);
DISPLAY INVISIBLE (-1275 1475);
FORCEPROP 2 LAST CDS_LIB mstr_discrete
J 0
(-1325 1375);
PAINT ORANGE (-1325 1375);
DISPLAY INVISIBLE (-1325 1375);
FORCEADD GND..1
(-1325 975);
FORCEPROP 3 LASTPIN (-1325 1025) SIG_NAME GND\g
J 0
(-1315 1035);
DISPLAY 0.659574 (-1315 1035);
PAINT MONO (-1315 1035);
DISPLAY INVISIBLE (-1315 1035);
FORCEPROP 1 LAST HDL_POWER GND
J 0
(-1325 1125);
DISPLAY 1.723404 (-1325 1125);
PAINT GREEN (-1325 1125);
DISPLAY INVISIBLE (-1325 1125);
FORCEPROP 2 LAST BOM_COST PROC_VRD_VCCIN_CPU0
J 0
(-1700 1050);
DISPLAY 1.446809 (-1700 1050);
PAINT MONO (-1700 1050);
DISPLAY INVISIBLE (-1700 1050);
FORCEPROP 2 LAST ROOM PVSA_CPU1_DECAP_VR
J 0
(-1875 1050);
DISPLAY 1.936170 (-1875 1050);
PAINT ORANGE (-1875 1050);
DISPLAY INVISIBLE (-1875 1050);
FORCEPROP 1 LAST VOLTAGE 0
J 0
(-1325 975);
PAINT SKYBLUE (-1325 975);
DISPLAY INVISIBLE (-1325 975);
FORCEPROP 1 LAST SIZE 1B
J 0
(-1250 925);
DISPLAY 1.723404 (-1250 925);
PAINT GREEN (-1250 925);
DISPLAY INVISIBLE (-1250 925);
FORCEPROP 2 LAST CDS_LIB mstr_symbols
J 0
(-1325 975);
PAINT ORANGE (-1325 975);
DISPLAY INVISIBLE (-1325 975);
FORCEPROP 1 LAST BODY_TYPE PLUMBING
J 0
(-1370 932);
DISPLAY 0.340426 (-1370 932);
PAINT GREEN (-1370 932);
DISPLAY INVISIBLE (-1370 932);
FORCEPROP 1 LAST PATH I13
J 0
(-1250 975);
DISPLAY 0.872340 (-1250 975);
PAINT AQUA (-1250 975);
DISPLAY INVISIBLE (-1250 975);
FORCEADD CAPP..1
R 2
(-1575 1375);
FORCEPROP 1 LASTPIN (-1575 1475) $PN 1
J 2
(-1585 1460);
DISPLAY 0.617021 (-1585 1460);
PAINT GREEN (-1585 1460);
FORCEPROP 1 LAST LOCATION C9N20
J 2
(-1625 1475);
DISPLAY 0.617021 (-1625 1475);
PAINT AQUA (-1625 1475);
FORCEPROP 1 LAST VALUE 470UF
J 2
(-1625 1425);
DISPLAY 0.617021 (-1625 1425);
PAINT SKYBLUE (-1625 1425);
FORCEPROP 1 LAST TOLERANCE 20%
J 2
(-1625 1375);
DISPLAY 0.617021 (-1625 1375);
PAINT SKYBLUE (-1625 1375);
FORCEPROP 1 LAST VOLTAGE 2.5V
J 2
(-1625 1325);
DISPLAY 0.617021 (-1625 1325);
PAINT SKYBLUE (-1625 1325);
FORCEPROP 1 LAST MATERIAL ALUM
J 2
(-1625 1275);
DISPLAY 0.617021 (-1625 1275);
PAINT SKYBLUE (-1625 1275);
FORCEPROP 1 LASTPIN (-1575 1275) $PN 2
J 2
(-1585 1260);
DISPLAY 0.617021 (-1585 1260);
PAINT GREEN (-1585 1260);
FORCEPROP 1 LAST PACK_TYPE 3018
J 2
(-1625 1225);
DISPLAY 0.617021 (-1625 1225);
PAINT SKYBLUE (-1625 1225);
FORCEPROP 1 LAST PART_NUMBER 699013-049
J 2
(-1625 1175);
DISPLAY 0.617021 (-1625 1175);
PAINT BLUE (-1625 1175);
FORCEPROP 2 LAST SEC_TYPE 3018
J 0
(-1615 1590);
DISPLAY 1.021277 (-1615 1590);
PAINT ORANGE (-1615 1590);
DISPLAY INVISIBLE (-1615 1590);
FORCEPROP 2 LAST SEC 1
J 0
(-1615 1590);
DISPLAY 0.680851 (-1615 1590);
PAINT MONO (-1615 1590);
DISPLAY INVISIBLE (-1615 1590);
FORCEPROP 2 LAST BOM_COST PROC_VRD_VCCIN_CPU0
J 2
(-1625 1525);
PAINT MONO (-1625 1525);
DISPLAY INVISIBLE (-1625 1525);
FORCEPROP 1 LAST PATH I14
J 2
(-1625 1525);
DISPLAY 0.978723 (-1625 1525);
PAINT ORANGE (-1625 1525);
DISPLAY INVISIBLE (-1625 1525);
FORCEPROP 2 LAST ROOM PVSA_CPU1_DECAP_VR
J 2
(-1625 1500);
PAINT MONO (-1625 1500);
DISPLAY INVISIBLE (-1625 1500);
FORCEPROP 2 LAST CDS_LOCATION C9N20
J 2
(-1625 1475);
DISPLAY 0.617021 (-1625 1475);
PAINT AQUA (-1625 1475);
DISPLAY INVISIBLE (-1625 1475);
FORCEPROP 2 LAST CDS_LIB mstr_discrete
J 2
(-1575 1375);
PAINT ORANGE (-1575 1375);
DISPLAY INVISIBLE (-1575 1375);
FORCEADD GND..1
(-3100 2900);
FORCEPROP 3 LASTPIN (-3100 2950) SIG_NAME GND\g
J 0
(-3090 2960);
DISPLAY 0.659574 (-3090 2960);
PAINT MONO (-3090 2960);
DISPLAY INVISIBLE (-3090 2960);
FORCEPROP 1 LAST SIZE 1B
J 0
(-3025 2850);
DISPLAY 1.723404 (-3025 2850);
PAINT GREEN (-3025 2850);
DISPLAY INVISIBLE (-3025 2850);
FORCEPROP 1 LAST PATH I15
J 0
(-3025 2900);
DISPLAY 0.872340 (-3025 2900);
PAINT AQUA (-3025 2900);
DISPLAY INVISIBLE (-3025 2900);
FORCEPROP 1 LAST HDL_POWER GND
J 0
(-3100 3050);
DISPLAY 1.723404 (-3100 3050);
PAINT GREEN (-3100 3050);
DISPLAY INVISIBLE (-3100 3050);
FORCEPROP 1 LAST VOLTAGE 0
J 0
(-3100 2900);
PAINT SKYBLUE (-3100 2900);
DISPLAY INVISIBLE (-3100 2900);
FORCEPROP 2 LAST CDS_LIB mstr_symbols
J 0
(-3100 2900);
PAINT ORANGE (-3100 2900);
DISPLAY INVISIBLE (-3100 2900);
FORCEPROP 1 LAST BODY_TYPE PLUMBING
J 0
(-3145 2857);
DISPLAY 0.340426 (-3145 2857);
PAINT GREEN (-3145 2857);
DISPLAY INVISIBLE (-3145 2857);
FORCEPROP 2 LAST BOM_COST PROC_VRD_VCCIN_CPU0
J 0
(-3475 2975);
DISPLAY 1.446809 (-3475 2975);
PAINT MONO (-3475 2975);
DISPLAY INVISIBLE (-3475 2975);
FORCEPROP 2 LAST ROOM PVSA_CPU1_PWR_VR
J 0
(-3650 2975);
DISPLAY 1.936170 (-3650 2975);
PAINT ORANGE (-3650 2975);
DISPLAY INVISIBLE (-3650 2975);
FORCEADD OFFPAGE..2
(-3950 1925);
FORCEPROP 2 LAST $XR0 73 
J 0
(-3761 1925);
DISPLAY 0.638298 (-3761 1925);
PAINT MONO (-3761 1925);
FORCEPROP 2 LAST BOM_COST PROC_VRD_VCCIN_CPU0
J 0
(-3625 1975);
PAINT MONO (-3625 1975);
DISPLAY INVISIBLE (-3625 1975);
FORCEPROP 1 LAST OFFPAGE TRUE
J 0
(-3625 1800);
DISPLAY 0.893617 (-3625 1800);
PAINT GREEN (-3625 1800);
DISPLAY INVISIBLE (-3625 1800);
FORCEPROP 2 LAST PATH I17
J 0
(-3785 1985);
DISPLAY 1.021277 (-3785 1985);
PAINT ORANGE (-3785 1985);
DISPLAY INVISIBLE (-3785 1985);
FORCEPROP 2 LAST CDS_LIB mstr_standard
J 0
(-3950 1925);
PAINT ORANGE (-3950 1925);
DISPLAY INVISIBLE (-3950 1925);
FORCEPROP 1 LAST COMMENT_BODY TRUE
J 0
(-3995 1830);
DISPLAY 0.893617 (-3995 1830);
PAINT GREEN (-3995 1830);
DISPLAY INVISIBLE (-3995 1830);
FORCEPROP 2 LAST ROOM PVSA_CPU1_VSENSE_VR
J 0
(-4350 2000);
PAINT ORANGE (-4350 2000);
DISPLAY INVISIBLE (-4350 2000);
FORCEADD OFFPAGE..2
(-3950 1475);
FORCEPROP 2 LAST $XR0 73 
J 0
(-3761 1475);
DISPLAY 0.638298 (-3761 1475);
PAINT MONO (-3761 1475);
FORCEPROP 2 LAST BOM_COST PROC_VRD_VCCIN_CPU0
J 0
(-3750 1525);
PAINT MONO (-3750 1525);
DISPLAY INVISIBLE (-3750 1525);
FORCEPROP 2 LAST PATH I18
J 0
(-3785 1535);
DISPLAY 1.021277 (-3785 1535);
PAINT ORANGE (-3785 1535);
DISPLAY INVISIBLE (-3785 1535);
FORCEPROP 1 LAST OFFPAGE TRUE
J 0
(-3625 1350);
DISPLAY 0.893617 (-3625 1350);
PAINT GREEN (-3625 1350);
DISPLAY INVISIBLE (-3625 1350);
FORCEPROP 2 LAST CDS_LIB mstr_standard
J 0
(-3950 1475);
PAINT ORANGE (-3950 1475);
DISPLAY INVISIBLE (-3950 1475);
FORCEPROP 1 LAST COMMENT_BODY TRUE
J 0
(-3995 1380);
DISPLAY 0.893617 (-3995 1380);
PAINT GREEN (-3995 1380);
DISPLAY INVISIBLE (-3995 1380);
FORCEPROP 2 LAST ROOM PVSA_CPU1_VSENSE_VR
J 0
(-4350 1550);
PAINT ORANGE (-4350 1550);
DISPLAY INVISIBLE (-4350 1550);
FORCEADD OFFPAGE..2
(-1475 4150);
FORCEPROP 2 LAST $XR0 206 
J 0
(-1286 4150);
DISPLAY 0.638298 (-1286 4150);
PAINT MONO (-1286 4150);
FORCEPROP 2 LAST BOM_COST PROC_VRD_VCCIN_CPU0
J 0
(-1275 4200);
DISPLAY 1.446809 (-1275 4200);
PAINT MONO (-1275 4200);
DISPLAY INVISIBLE (-1275 4200);
FORCEPROP 2 LAST PATH I2
J 0
(-1045 4200);
DISPLAY 1.021277 (-1045 4200);
PAINT ORANGE (-1045 4200);
DISPLAY INVISIBLE (-1045 4200);
FORCEPROP 2 LAST CDS_LIB mstr_standard
J 0
(-1475 4150);
PAINT ORANGE (-1475 4150);
DISPLAY INVISIBLE (-1475 4150);
FORCEPROP 2 LAST ROOM PVSA_CPU1_PWR_VR
J 0
(-1875 4225);
DISPLAY 1.936170 (-1875 4225);
PAINT ORANGE (-1875 4225);
DISPLAY INVISIBLE (-1875 4225);
FORCEPROP 1 LAST OFFPAGE TRUE
J 0
(-1150 4025);
DISPLAY 1.723404 (-1150 4025);
PAINT GREEN (-1150 4025);
DISPLAY INVISIBLE (-1150 4025);
FORCEPROP 1 LAST COMMENT_BODY TRUE
J 0
(-1520 4055);
DISPLAY 1.723404 (-1520 4055);
PAINT GREEN (-1520 4055);
DISPLAY INVISIBLE (-1520 4055);
FORCEADD RES..1
(-5700 4425);
FORCEPROP 1 LAST MATERIAL CHIP
J 0
(-5625 4250);
DISPLAY 0.617021 (-5625 4250);
PAINT SKYBLUE (-5625 4250);
FORCEPROP 1 LAST PART_NUMBER G21796-090
J 0
(-5825 4350);
DISPLAY 0.617021 (-5825 4350);
PAINT BLUE (-5825 4350);
FORCEPROP 1 LAST PACK_TYPE 0402
J 0
(-5650 4300);
DISPLAY 0.617021 (-5650 4300);
PAINT SKYBLUE (-5650 4300);
FORCEPROP 1 LASTPIN (-5600 4425) $PN 2
J 0
(-5638 4437);
DISPLAY 0.617021 (-5638 4437);
PAINT ORANGE (-5638 4437);
FORCEPROP 1 LAST LOCATION R9N3
J 0
(-5750 4475);
DISPLAY 0.617021 (-5750 4475);
PAINT AQUA (-5750 4475);
FORCEPROP 1 LASTPIN (-5800 4425) $PN 1
J 0
(-5788 4437);
DISPLAY 0.617021 (-5788 4437);
PAINT ORANGE (-5788 4437);
FORCEPROP 1 LAST TOLERANCE 1%
J 0
(-5750 4300);
DISPLAY 0.617021 (-5750 4300);
PAINT SKYBLUE (-5750 4300);
FORCEPROP 1 LAST VALUE 1.0
J 2
(-5800 4300);
DISPLAY 0.617021 (-5800 4300);
PAINT SKYBLUE (-5800 4300);
FORCEPROP 1 LAST WATTAGE 1/16W
J 2
(-5675 4250);
DISPLAY 0.617021 (-5675 4250);
PAINT SKYBLUE (-5675 4250);
FORCEPROP 2 LAST SEC 1
J 0
(-5750 4625);
DISPLAY 0.680851 (-5750 4625);
PAINT MONO (-5750 4625);
DISPLAY INVISIBLE (-5750 4625);
FORCEPROP 2 LAST SEC_TYPE 0402
J 0
(-5750 4625);
DISPLAY 1.021277 (-5750 4625);
PAINT ORANGE (-5750 4625);
DISPLAY INVISIBLE (-5750 4625);
FORCEPROP 1 LAST PATH I20
J 0
(-5750 4575);
DISPLAY 0.978723 (-5750 4575);
PAINT WHITE (-5750 4575);
DISPLAY INVISIBLE (-5750 4575);
FORCEPROP 2 LAST CDS_LOCATION R9N3
J 0
(-5750 4475);
DISPLAY 0.617021 (-5750 4475);
PAINT AQUA (-5750 4475);
DISPLAY INVISIBLE (-5750 4475);
FORCEPROP 2 LAST CDS_LIB mstr_discrete
J 0
(-5700 4425);
PAINT ORANGE (-5700 4425);
DISPLAY INVISIBLE (-5700 4425);
FORCEPROP 2 LAST ROOM PVSA_CPU1_PWR_VR
J 0
(-5750 4525);
DISPLAY 1.361702 (-5750 4525);
PAINT ORANGE (-5750 4525);
DISPLAY INVISIBLE (-5750 4525);
FORCEADD VCC_CORE..1
(-7400 4225);
FORCEPROP 3 LASTPIN (-7400 4175) SIG_NAME VR_FET_SW_P12V_STBY_PVCCIN_CPU1\g
J 0
(-7390 4185);
DISPLAY 0.659574 (-7390 4185);
PAINT MONO (-7390 4185);
DISPLAY INVISIBLE (-7390 4185);
FORCEPROP 1 LAST HDL_POWER VR_FET_SW_P12V_STBY_PVCCIN_CPU1
J 1
(-7350 4275);
DISPLAY 0.617021 (-7350 4275);
PAINT GREEN (-7350 4275);
FORCEPROP 2 LAST CDS_LIB mstr_symbols
J 0
(-7400 4225);
PAINT ORANGE (-7400 4225);
DISPLAY INVISIBLE (-7400 4225);
FORCEPROP 1 LAST PATH I21
J 0
(-7350 4250);
DISPLAY 0.872340 (-7350 4250);
PAINT AQUA (-7350 4250);
DISPLAY INVISIBLE (-7350 4250);
FORCEADD CAP..1
(-5375 3850);
FORCEPROP 1 LAST PART_NUMBER A36096-155
J 0
(-5325 3675);
DISPLAY 0.617021 (-5325 3675);
PAINT BLUE (-5325 3675);
FORCEPROP 1 LASTPIN (-5375 3950) $PN 1
J 0
(-5365 3930);
DISPLAY 0.617021 (-5365 3930);
PAINT ORANGE (-5365 3930);
FORCEPROP 1 LAST VALUE 0.22UF
J 0
(-5325 3875);
DISPLAY 0.617021 (-5325 3875);
PAINT SKYBLUE (-5325 3875);
FORCEPROP 1 LAST LOCATION C1C4
J 0
(-5325 3925);
DISPLAY 0.617021 (-5325 3925);
PAINT AQUA (-5325 3925);
FORCEPROP 1 LAST VOLTAGE 16V
J 0
(-5325 3825);
DISPLAY 0.617021 (-5325 3825);
PAINT SKYBLUE (-5325 3825);
FORCEPROP 1 LAST TOLERANCE 10%
J 0
(-5325 3775);
DISPLAY 0.617021 (-5325 3775);
PAINT SKYBLUE (-5325 3775);
FORCEPROP 1 LAST PACK_TYPE 0402
J 0
(-5325 3625);
DISPLAY 0.617021 (-5325 3625);
PAINT SKYBLUE (-5325 3625);
FORCEPROP 1 LAST MATERIAL X7R
J 0
(-5325 3725);
DISPLAY 0.617021 (-5325 3725);
PAINT SKYBLUE (-5325 3725);
FORCEPROP 1 LASTPIN (-5375 3750) $PN 2
J 0
(-5365 3730);
DISPLAY 0.617021 (-5365 3730);
PAINT ORANGE (-5365 3730);
FORCEPROP 2 LAST ROOM PVSA_CPU1_PWR_VR
J 0
(-5325 4000);
DISPLAY 1.361702 (-5325 4000);
PAINT ORANGE (-5325 4000);
DISPLAY INVISIBLE (-5325 4000);
FORCEPROP 1 LAST PATH I22
J 0
(-5325 4000);
DISPLAY 0.978723 (-5325 4000);
PAINT WHITE (-5325 4000);
DISPLAY INVISIBLE (-5325 4000);
FORCEPROP 2 LAST CDS_LOCATION C1C4
J 0
(-5325 3925);
DISPLAY 0.617021 (-5325 3925);
PAINT AQUA (-5325 3925);
DISPLAY INVISIBLE (-5325 3925);
FORCEPROP 2 LAST SEC 1
J 0
(-5325 4050);
DISPLAY 0.680851 (-5325 4050);
PAINT MONO (-5325 4050);
DISPLAY INVISIBLE (-5325 4050);
FORCEPROP 2 LAST SEC_TYPE 0402
J 0
(-5325 4050);
DISPLAY 1.021277 (-5325 4050);
PAINT ORANGE (-5325 4050);
DISPLAY INVISIBLE (-5325 4050);
FORCEPROP 2 LAST CDS_LIB mstr_discrete
J 0
(-5375 3850);
PAINT ORANGE (-5375 3850);
DISPLAY INVISIBLE (-5375 3850);
FORCEADD CAP_A..1
R 2
(-5500 3850);
FORCEPROP 1 LAST PART_NUMBER D97712-004
J 2
(-5550 3700);
DISPLAY 0.617021 (-5550 3700);
PAINT BLUE (-5550 3700);
FORCEPROP 1 LAST PACK_TYPE 0402V
J 2
(-5550 3650);
DISPLAY 0.617021 (-5550 3650);
PAINT SKYBLUE (-5550 3650);
FORCEPROP 1 LASTPIN (-5500 3950) $PN 1
J 2
(-5510 3930);
DISPLAY 0.617021 (-5510 3930);
PAINT ORANGE (-5510 3930);
FORCEPROP 1 LASTPIN (-5500 3750) $PN 2
J 2
(-5510 3730);
DISPLAY 0.617021 (-5510 3730);
PAINT ORANGE (-5510 3730);
FORCEPROP 1 LAST LOCATION C1C3
J 2
(-5550 3925);
DISPLAY 0.617021 (-5550 3925);
PAINT AQUA (-5550 3925);
FORCEPROP 1 LAST VALUE 1.0UF
J 2
(-5550 3900);
DISPLAY 0.617021 (-5550 3900);
PAINT SKYBLUE (-5550 3900);
FORCEPROP 1 LAST TOLERANCE 10%
J 2
(-5550 3800);
DISPLAY 0.617021 (-5550 3800);
PAINT SKYBLUE (-5550 3800);
FORCEPROP 1 LAST VOLTAGE 6.3V
J 2
(-5550 3850);
DISPLAY 0.617021 (-5550 3850);
PAINT SKYBLUE (-5550 3850);
FORCEPROP 1 LAST MATERIAL X6S
J 2
(-5550 3750);
DISPLAY 0.617021 (-5550 3750);
PAINT SKYBLUE (-5550 3750);
FORCEPROP 2 LAST ROOM PVSA_CPU1_PWR_VR
J 0
(-5550 4000);
DISPLAY 1.361702 (-5550 4000);
PAINT ORANGE (-5550 4000);
DISPLAY INVISIBLE (-5550 4000);
FORCEPROP 1 LAST PATH I23
J 2
(-5550 4000);
DISPLAY 0.978723 (-5550 4000);
PAINT WHITE (-5550 4000);
DISPLAY INVISIBLE (-5550 4000);
FORCEPROP 2 LAST SEC 1
J 0
(-5550 4050);
DISPLAY 0.680851 (-5550 4050);
PAINT MONO (-5550 4050);
DISPLAY INVISIBLE (-5550 4050);
FORCEPROP 2 LAST SEC_TYPE 0402V
J 0
(-5550 4050);
DISPLAY 1.021277 (-5550 4050);
PAINT ORANGE (-5550 4050);
DISPLAY INVISIBLE (-5550 4050);
FORCEPROP 2 LAST CDS_SEC 1
J 0
(-5550 3975);
PAINT ORANGE (-5550 3975);
DISPLAY INVISIBLE (-5550 3975);
FORCEPROP 2 LAST CDS_LIB dev_discrete
J 0
(-5500 3850);
PAINT ORANGE (-5500 3850);
DISPLAY INVISIBLE (-5500 3850);
FORCEPROP 2 LAST CDS_LOCATION C1C3
J 2
(-5550 3925);
DISPLAY 0.617021 (-5550 3925);
PAINT AQUA (-5550 3925);
DISPLAY INVISIBLE (-5550 3925);
FORCEADD CAP..1
R 2
(-6125 3250);
FORCEPROP 1 LAST VOLTAGE 16V
J 2
(-6175 3250);
DISPLAY 0.617021 (-6175 3250);
PAINT SKYBLUE (-6175 3250);
FORCEPROP 1 LASTPIN (-6125 3350) $PN 1
J 2
(-6135 3330);
DISPLAY 0.617021 (-6135 3330);
PAINT ORANGE (-6135 3330);
FORCEPROP 1 LASTPIN (-6125 3150) $PN 2
J 2
(-6135 3130);
DISPLAY 0.617021 (-6135 3130);
PAINT ORANGE (-6135 3130);
FORCEPROP 1 LAST LOCATION C1C12
J 2
(-6175 3350);
DISPLAY 0.617021 (-6175 3350);
PAINT AQUA (-6175 3350);
FORCEPROP 1 LAST PART_NUMBER A36096-104
J 2
(-6175 3100);
DISPLAY 0.617021 (-6175 3100);
PAINT BLUE (-6175 3100);
FORCEPROP 1 LAST VALUE 0.220UF
J 2
(-6175 3300);
DISPLAY 0.617021 (-6175 3300);
PAINT SKYBLUE (-6175 3300);
FORCEPROP 1 LAST TOLERANCE 10%
J 2
(-6175 3200);
DISPLAY 0.617021 (-6175 3200);
PAINT SKYBLUE (-6175 3200);
FORCEPROP 1 LAST PACK_TYPE 0402
J 2
(-6175 3050);
DISPLAY 0.617021 (-6175 3050);
PAINT SKYBLUE (-6175 3050);
FORCEPROP 1 LAST MATERIAL X7R
J 2
(-6175 3150);
DISPLAY 0.617021 (-6175 3150);
PAINT SKYBLUE (-6175 3150);
FORCEPROP 2 LAST CDS_LOCATION C1C12
J 2
(-6175 3350);
DISPLAY 0.617021 (-6175 3350);
PAINT AQUA (-6175 3350);
DISPLAY INVISIBLE (-6175 3350);
FORCEPROP 2 LAST SEC 1
J 0
(-6175 3450);
DISPLAY 0.680851 (-6175 3450);
PAINT MONO (-6175 3450);
DISPLAY INVISIBLE (-6175 3450);
FORCEPROP 0 LAST SPOF TRUE
J 0
(-6175 3450);
DISPLAY 1.021277 (-6175 3450);
PAINT ORANGE (-6175 3450);
DISPLAY INVISIBLE (-6175 3450);
FORCEPROP 2 LAST ROOM PVSA_CPU1_PWR_VR
J 0
(-6175 3400);
DISPLAY 1.361702 (-6175 3400);
PAINT ORANGE (-6175 3400);
DISPLAY INVISIBLE (-6175 3400);
FORCEPROP 2 LAST SEC_TYPE 0402
J 0
(-6175 3450);
DISPLAY 1.021277 (-6175 3450);
PAINT ORANGE (-6175 3450);
DISPLAY INVISIBLE (-6175 3450);
FORCEPROP 1 LAST PATH I24
J 2
(-6175 3400);
DISPLAY 0.978723 (-6175 3400);
PAINT WHITE (-6175 3400);
DISPLAY INVISIBLE (-6175 3400);
FORCEPROP 2 LAST CDS_LIB mstr_discrete
J 0
(-6125 3250);
PAINT ORANGE (-6125 3250);
DISPLAY INVISIBLE (-6125 3250);
FORCEADD CAP..1
(-6025 3825);
FORCEPROP 1 LAST TOLERANCE 10%
J 0
(-5975 3775);
DISPLAY 0.617021 (-5975 3775);
PAINT SKYBLUE (-5975 3775);
FORCEPROP 1 LAST PACK_TYPE 0402
J 0
(-5975 3625);
DISPLAY 0.617021 (-5975 3625);
PAINT SKYBLUE (-5975 3625);
FORCEPROP 1 LAST PART_NUMBER D97712-011
J 0
(-5975 3675);
DISPLAY 0.617021 (-5975 3675);
PAINT BLUE (-5975 3675);
FORCEPROP 1 LAST MATERIAL X6S
J 0
(-5975 3725);
DISPLAY 0.617021 (-5975 3725);
PAINT SKYBLUE (-5975 3725);
FORCEPROP 1 LAST VOLTAGE 16V
J 0
(-5975 3825);
DISPLAY 0.617021 (-5975 3825);
PAINT SKYBLUE (-5975 3825);
FORCEPROP 1 LAST VALUE 1.0UF
J 0
(-5975 3875);
DISPLAY 0.617021 (-5975 3875);
PAINT SKYBLUE (-5975 3875);
FORCEPROP 1 LAST LOCATION C1C5
J 0
(-5975 3925);
DISPLAY 0.617021 (-5975 3925);
PAINT AQUA (-5975 3925);
FORCEPROP 1 LASTPIN (-6025 3925) $PN 1
J 0
(-6015 3905);
DISPLAY 0.617021 (-6015 3905);
PAINT ORANGE (-6015 3905);
FORCEPROP 1 LASTPIN (-6025 3725) $PN 2
J 0
(-6015 3705);
DISPLAY 0.617021 (-6015 3705);
PAINT ORANGE (-6015 3705);
FORCEPROP 2 LAST ROOM PVSA_CPU1_PWR_VR
J 0
(-5975 3975);
DISPLAY 1.361702 (-5975 3975);
PAINT ORANGE (-5975 3975);
DISPLAY INVISIBLE (-5975 3975);
FORCEPROP 1 LAST PATH I26
J 0
(-5975 3975);
DISPLAY 0.978723 (-5975 3975);
PAINT WHITE (-5975 3975);
DISPLAY INVISIBLE (-5975 3975);
FORCEPROP 2 LAST CDS_LOCATION C1C5
J 0
(-5975 3925);
DISPLAY 0.617021 (-5975 3925);
PAINT AQUA (-5975 3925);
DISPLAY INVISIBLE (-5975 3925);
FORCEPROP 2 LAST SEC 1
J 0
(-5975 4025);
DISPLAY 0.680851 (-5975 4025);
PAINT MONO (-5975 4025);
DISPLAY INVISIBLE (-5975 4025);
FORCEPROP 2 LAST SEC_TYPE 0402
J 0
(-5975 4025);
DISPLAY 1.021277 (-5975 4025);
PAINT ORANGE (-5975 4025);
DISPLAY INVISIBLE (-5975 4025);
FORCEPROP 2 LAST CDS_LIB mstr_discrete
J 0
(-6025 3825);
PAINT ORANGE (-6025 3825);
DISPLAY INVISIBLE (-6025 3825);
FORCEADD CAP_A..1
(-6325 3850);
FORCEPROP 1 LAST PART_NUMBER A36096-030
J 0
(-6275 3700);
DISPLAY 0.617021 (-6275 3700);
PAINT BLUE (-6275 3700);
FORCEPROP 1 LAST PACK_TYPE 0402V
J 0
(-6275 3650);
DISPLAY 0.617021 (-6275 3650);
PAINT SKYBLUE (-6275 3650);
FORCEPROP 1 LAST MATERIAL X7R
J 0
(-6275 3750);
DISPLAY 0.617021 (-6275 3750);
PAINT SKYBLUE (-6275 3750);
FORCEPROP 1 LAST LOCATION C1C17
J 0
(-6275 3950);
DISPLAY 0.617021 (-6275 3950);
PAINT AQUA (-6275 3950);
FORCEPROP 1 LAST VALUE 0.1UF
J 0
(-6275 3900);
DISPLAY 0.617021 (-6275 3900);
PAINT SKYBLUE (-6275 3900);
FORCEPROP 1 LAST VOLTAGE 16V
J 0
(-6275 3850);
DISPLAY 0.617021 (-6275 3850);
PAINT SKYBLUE (-6275 3850);
FORCEPROP 1 LASTPIN (-6325 3950) $PN 1
J 0
(-6315 3930);
DISPLAY 0.617021 (-6315 3930);
PAINT ORANGE (-6315 3930);
FORCEPROP 1 LAST TOLERANCE 10%
J 0
(-6275 3800);
DISPLAY 0.617021 (-6275 3800);
PAINT SKYBLUE (-6275 3800);
FORCEPROP 1 LASTPIN (-6325 3750) $PN 2
J 0
(-6315 3730);
DISPLAY 0.617021 (-6315 3730);
PAINT ORANGE (-6315 3730);
FORCEPROP 2 LAST SEC 1
J 0
(-6275 4050);
DISPLAY 0.680851 (-6275 4050);
PAINT MONO (-6275 4050);
DISPLAY INVISIBLE (-6275 4050);
FORCEPROP 2 LAST SEC_TYPE 0402V
J 0
(-6275 4050);
DISPLAY 1.021277 (-6275 4050);
PAINT ORANGE (-6275 4050);
DISPLAY INVISIBLE (-6275 4050);
FORCEPROP 2 LAST CDS_SEC 1
J 0
(-6275 4000);
PAINT ORANGE (-6275 4000);
DISPLAY INVISIBLE (-6275 4000);
FORCEPROP 2 LAST ROOM PVSA_CPU1_PWR_VR
J 0
(-6275 4000);
DISPLAY 1.361702 (-6275 4000);
PAINT ORANGE (-6275 4000);
DISPLAY INVISIBLE (-6275 4000);
FORCEPROP 1 LAST PATH I27
J 0
(-6275 4000);
DISPLAY 0.978723 (-6275 4000);
PAINT WHITE (-6275 4000);
DISPLAY INVISIBLE (-6275 4000);
FORCEPROP 2 LAST CDS_LOCATION C1C17
J 0
(-6275 3950);
DISPLAY 0.617021 (-6275 3950);
PAINT AQUA (-6275 3950);
DISPLAY INVISIBLE (-6275 3950);
FORCEPROP 2 LAST CDS_LIB dev_discrete
J 0
(-6325 3850);
PAINT ORANGE (-6325 3850);
DISPLAY INVISIBLE (-6325 3850);
FORCEADD CAP..1
(-6600 3850);
FORCEPROP 1 LAST TOLERANCE 10%
J 0
(-6550 3800);
DISPLAY 0.617021 (-6550 3800);
PAINT SKYBLUE (-6550 3800);
FORCEPROP 1 LAST MATERIAL X6S
J 0
(-6550 3750);
DISPLAY 0.617021 (-6550 3750);
PAINT SKYBLUE (-6550 3750);
FORCEPROP 1 LAST PART_NUMBER D97712-011
J 0
(-6550 3700);
DISPLAY 0.617021 (-6550 3700);
PAINT BLUE (-6550 3700);
FORCEPROP 1 LAST LOCATION C1C15
J 0
(-6550 3950);
DISPLAY 0.617021 (-6550 3950);
PAINT AQUA (-6550 3950);
FORCEPROP 1 LAST VALUE 1.0UF
J 0
(-6550 3900);
DISPLAY 0.617021 (-6550 3900);
PAINT SKYBLUE (-6550 3900);
FORCEPROP 1 LAST VOLTAGE 16V
J 0
(-6550 3850);
DISPLAY 0.617021 (-6550 3850);
PAINT SKYBLUE (-6550 3850);
FORCEPROP 1 LASTPIN (-6600 3950) $PN 1
J 0
(-6590 3930);
DISPLAY 0.617021 (-6590 3930);
PAINT ORANGE (-6590 3930);
FORCEPROP 1 LAST PACK_TYPE 0402
J 0
(-6550 3650);
DISPLAY 0.617021 (-6550 3650);
PAINT SKYBLUE (-6550 3650);
FORCEPROP 1 LASTPIN (-6600 3750) $PN 2
J 0
(-6590 3730);
DISPLAY 0.617021 (-6590 3730);
PAINT ORANGE (-6590 3730);
FORCEPROP 2 LAST ROOM PVSA_CPU1_PWR_VR
J 0
(-6550 4000);
DISPLAY 1.361702 (-6550 4000);
PAINT ORANGE (-6550 4000);
DISPLAY INVISIBLE (-6550 4000);
FORCEPROP 1 LAST PATH I28
J 0
(-6550 4000);
DISPLAY 0.978723 (-6550 4000);
PAINT WHITE (-6550 4000);
DISPLAY INVISIBLE (-6550 4000);
FORCEPROP 2 LAST SEC 1
J 0
(-6550 4050);
DISPLAY 0.680851 (-6550 4050);
PAINT MONO (-6550 4050);
DISPLAY INVISIBLE (-6550 4050);
FORCEPROP 2 LAST SEC_TYPE 0402
J 0
(-6550 4050);
DISPLAY 1.021277 (-6550 4050);
PAINT ORANGE (-6550 4050);
DISPLAY INVISIBLE (-6550 4050);
FORCEPROP 2 LAST CDS_LOCATION C1C15
J 0
(-6550 3950);
DISPLAY 0.617021 (-6550 3950);
PAINT AQUA (-6550 3950);
DISPLAY INVISIBLE (-6550 3950);
FORCEPROP 2 LAST CDS_LIB mstr_discrete
J 0
(-6600 3850);
PAINT ORANGE (-6600 3850);
DISPLAY INVISIBLE (-6600 3850);
FORCEADD RES..1
(-5300 2325);
FORCEPROP 1 LAST LOCATION R1C12
J 0
(-5350 2375);
DISPLAY 0.617021 (-5350 2375);
PAINT AQUA (-5350 2375);
FORCEPROP 1 LASTPIN (-5200 2325) $PN 2
J 0
(-5238 2337);
DISPLAY 0.617021 (-5238 2337);
PAINT ORANGE (-5238 2337);
FORCEPROP 1 LAST TOLERANCE 1%
J 0
(-5250 2250);
DISPLAY 0.617021 (-5250 2250);
PAINT SKYBLUE (-5250 2250);
FORCEPROP 1 LAST PACK_TYPE 0402
J 0
(-5375 2150);
DISPLAY 0.617021 (-5375 2150);
PAINT SKYBLUE (-5375 2150);
FORCEPROP 1 LAST VALUE 100.0
J 2
(-5300 2250);
DISPLAY 0.617021 (-5300 2250);
PAINT SKYBLUE (-5300 2250);
FORCEPROP 1 LAST WATTAGE 1/16W
J 2
(-5300 2200);
DISPLAY 0.617021 (-5300 2200);
PAINT SKYBLUE (-5300 2200);
FORCEPROP 1 LASTPIN (-5400 2325) $PN 1
J 0
(-5388 2337);
DISPLAY 0.617021 (-5388 2337);
PAINT ORANGE (-5388 2337);
FORCEPROP 1 LAST PART_NUMBER G21796-017
J 0
(-5350 2425);
DISPLAY 0.617021 (-5350 2425);
PAINT BLUE (-5350 2425);
FORCEPROP 2 LAST SEC_TYPE 0402
J 0
(-5335 2535);
DISPLAY 1.021277 (-5335 2535);
PAINT ORANGE (-5335 2535);
DISPLAY INVISIBLE (-5335 2535);
FORCEPROP 2 LAST SEC 1
J 0
(-5335 2535);
DISPLAY 0.680851 (-5335 2535);
PAINT MONO (-5335 2535);
DISPLAY INVISIBLE (-5335 2535);
FORCEPROP 2 LAST CDS_LOCATION R1C12
J 0
(-5350 2375);
DISPLAY 0.617021 (-5350 2375);
PAINT AQUA (-5350 2375);
DISPLAY INVISIBLE (-5350 2375);
FORCEPROP 1 LAST PATH I29
J 0
(-5350 2475);
DISPLAY 0.978723 (-5350 2475);
PAINT WHITE (-5350 2475);
DISPLAY INVISIBLE (-5350 2475);
FORCEPROP 2 LAST ROOM PVSA_CPU1_VSENSE_VR
J 0
(-5350 2425);
PAINT ORANGE (-5350 2425);
DISPLAY INVISIBLE (-5350 2425);
FORCEPROP 2 LAST CDS_LIB mstr_discrete
J 0
(-5300 2325);
PAINT ORANGE (-5300 2325);
DISPLAY INVISIBLE (-5300 2325);
FORCEPROP 2 LAST BOM_COST PROC_VRD_VCCIN_CPU0
J 0
(-5350 2475);
PAINT MONO (-5350 2475);
DISPLAY INVISIBLE (-5350 2475);
FORCEPROP 1 LAST MATERIAL CHIP
J 0
(-5275 2200);
PAINT SKYBLUE (-5275 2200);
DISPLAY INVISIBLE (-5275 2200);
FORCEADD GND..1
(-4450 950);
FORCEPROP 3 LASTPIN (-4450 1000) SIG_NAME GND\g
J 0
(-4440 1010);
DISPLAY 0.659574 (-4440 1010);
PAINT MONO (-4440 1010);
DISPLAY INVISIBLE (-4440 1010);
FORCEPROP 1 LAST HDL_POWER GND
J 0
(-4450 1100);
DISPLAY 0.893617 (-4450 1100);
PAINT GREEN (-4450 1100);
DISPLAY INVISIBLE (-4450 1100);
FORCEPROP 2 LAST ROOM PVSA_CPU1_VSENSE_VR
J 0
(-5000 1025);
PAINT ORANGE (-5000 1025);
DISPLAY INVISIBLE (-5000 1025);
FORCEPROP 2 LAST BOM_COST PROC_VRD_VCCIN_CPU0
J 0
(-4825 1025);
PAINT MONO (-4825 1025);
DISPLAY INVISIBLE (-4825 1025);
FORCEPROP 1 LAST VOLTAGE 0
J 0
(-4450 950);
PAINT SKYBLUE (-4450 950);
DISPLAY INVISIBLE (-4450 950);
FORCEPROP 1 LAST PATH I30
J 0
(-4375 950);
DISPLAY 0.872340 (-4375 950);
PAINT AQUA (-4375 950);
DISPLAY INVISIBLE (-4375 950);
FORCEPROP 2 LAST CDS_LIB mstr_symbols
J 0
(-4450 950);
PAINT ORANGE (-4450 950);
DISPLAY INVISIBLE (-4450 950);
FORCEPROP 1 LAST SIZE 1B
J 0
(-4375 900);
DISPLAY 0.893617 (-4375 900);
PAINT GREEN (-4375 900);
DISPLAY INVISIBLE (-4375 900);
FORCEPROP 1 LAST BODY_TYPE PLUMBING
J 0
(-4495 907);
DISPLAY 0.340426 (-4495 907);
PAINT GREEN (-4495 907);
DISPLAY INVISIBLE (-4495 907);
FORCEADD RES..1
(-5275 1925);
FORCEPROP 1 LAST PART_NUMBER G21497-005
J 0
(-5400 2025);
DISPLAY 0.617021 (-5400 2025);
PAINT BLUE (-5400 2025);
FORCEPROP 1 LASTPIN (-5175 1925) $PN 2
J 0
(-5213 1937);
DISPLAY 0.617021 (-5213 1937);
PAINT ORANGE (-5213 1937);
FORCEPROP 1 LAST TOLERANCE 5%
J 0
(-5275 1850);
DISPLAY 0.617021 (-5275 1850);
PAINT SKYBLUE (-5275 1850);
FORCEPROP 1 LAST LOCATION R1C7
J 0
(-5325 1975);
DISPLAY 0.617021 (-5325 1975);
PAINT AQUA (-5325 1975);
FORCEPROP 1 LASTPIN (-5375 1925) $PN 1
J 0
(-5363 1937);
DISPLAY 0.617021 (-5363 1937);
PAINT ORANGE (-5363 1937);
FORCEPROP 1 LAST MATERIAL CHIP
J 0
(-5275 1775);
DISPLAY 0.617021 (-5275 1775);
PAINT SKYBLUE (-5275 1775);
FORCEPROP 1 LAST VALUE 0.0
J 2
(-5300 1850);
DISPLAY 0.617021 (-5300 1850);
PAINT SKYBLUE (-5300 1850);
FORCEPROP 1 LAST PACK_TYPE 0402
J 0
(-5400 1725);
DISPLAY 0.617021 (-5400 1725);
PAINT SKYBLUE (-5400 1725);
FORCEPROP 1 LAST WATTAGE 1/16W
J 2
(-5300 1775);
DISPLAY 0.617021 (-5300 1775);
PAINT SKYBLUE (-5300 1775);
FORCEPROP 2 LAST SEC_TYPE 0402
J 0
(-5310 2135);
DISPLAY 1.021277 (-5310 2135);
PAINT ORANGE (-5310 2135);
DISPLAY INVISIBLE (-5310 2135);
FORCEPROP 2 LAST SEC 1
J 0
(-5310 2135);
DISPLAY 0.680851 (-5310 2135);
PAINT MONO (-5310 2135);
DISPLAY INVISIBLE (-5310 2135);
FORCEPROP 1 LAST PATH I31
J 0
(-5325 2075);
DISPLAY 0.978723 (-5325 2075);
PAINT WHITE (-5325 2075);
DISPLAY INVISIBLE (-5325 2075);
FORCEPROP 2 LAST BOM_COST PROC_VRD_VCCIN_CPU0
J 0
(-5400 2075);
PAINT MONO (-5400 2075);
DISPLAY INVISIBLE (-5400 2075);
FORCEPROP 2 LAST ROOM PVSA_CPU1_VSENSE_VR
J 0
(-5325 2025);
PAINT ORANGE (-5325 2025);
DISPLAY INVISIBLE (-5325 2025);
FORCEPROP 2 LAST CDS_LOCATION R1C7
J 0
(-5325 1975);
DISPLAY 0.617021 (-5325 1975);
PAINT AQUA (-5325 1975);
DISPLAY INVISIBLE (-5325 1975);
FORCEPROP 2 LAST CDS_LIB mstr_discrete
J 0
(-5275 1925);
PAINT ORANGE (-5275 1925);
DISPLAY INVISIBLE (-5275 1925);
FORCEADD RES..1
(-5275 1475);
FORCEPROP 1 LASTPIN (-5375 1475) $PN 1
J 0
(-5363 1487);
DISPLAY 0.617021 (-5363 1487);
PAINT ORANGE (-5363 1487);
FORCEPROP 1 LAST VALUE 0.0
J 2
(-5300 1400);
DISPLAY 0.617021 (-5300 1400);
PAINT SKYBLUE (-5300 1400);
FORCEPROP 1 LAST PACK_TYPE 0402
J 0
(-5400 1275);
DISPLAY 0.617021 (-5400 1275);
PAINT SKYBLUE (-5400 1275);
FORCEPROP 1 LAST WATTAGE 1/16W
J 2
(-5300 1325);
DISPLAY 0.617021 (-5300 1325);
PAINT SKYBLUE (-5300 1325);
FORCEPROP 1 LASTPIN (-5175 1475) $PN 2
J 0
(-5213 1487);
DISPLAY 0.617021 (-5213 1487);
PAINT ORANGE (-5213 1487);
FORCEPROP 1 LAST MATERIAL CHIP
J 0
(-5275 1325);
DISPLAY 0.617021 (-5275 1325);
PAINT SKYBLUE (-5275 1325);
FORCEPROP 1 LAST TOLERANCE 5%
J 0
(-5275 1400);
DISPLAY 0.617021 (-5275 1400);
PAINT SKYBLUE (-5275 1400);
FORCEPROP 1 LAST LOCATION R1C5
J 0
(-5325 1525);
DISPLAY 0.617021 (-5325 1525);
PAINT AQUA (-5325 1525);
FORCEPROP 1 LAST PART_NUMBER G21497-005
J 0
(-5400 1575);
DISPLAY 0.617021 (-5400 1575);
PAINT BLUE (-5400 1575);
FORCEPROP 2 LAST SEC_TYPE 0402
J 0
(-5310 1685);
DISPLAY 1.021277 (-5310 1685);
PAINT ORANGE (-5310 1685);
DISPLAY INVISIBLE (-5310 1685);
FORCEPROP 2 LAST SEC 1
J 0
(-5310 1685);
DISPLAY 0.680851 (-5310 1685);
PAINT MONO (-5310 1685);
DISPLAY INVISIBLE (-5310 1685);
FORCEPROP 1 LAST PATH I32
J 0
(-5325 1625);
DISPLAY 0.978723 (-5325 1625);
PAINT WHITE (-5325 1625);
DISPLAY INVISIBLE (-5325 1625);
FORCEPROP 2 LAST ROOM PVSA_CPU1_VSENSE_VR
J 0
(-5325 1575);
PAINT ORANGE (-5325 1575);
DISPLAY INVISIBLE (-5325 1575);
FORCEPROP 2 LAST BOM_COST PROC_VRD_VCCIN_CPU0
J 0
(-5400 1625);
PAINT MONO (-5400 1625);
DISPLAY INVISIBLE (-5400 1625);
FORCEPROP 2 LAST CDS_LOCATION R1C5
J 0
(-5325 1525);
DISPLAY 0.617021 (-5325 1525);
PAINT AQUA (-5325 1525);
DISPLAY INVISIBLE (-5325 1525);
FORCEPROP 2 LAST CDS_LIB mstr_discrete
J 0
(-5275 1475);
PAINT ORANGE (-5275 1475);
DISPLAY INVISIBLE (-5275 1475);
FORCEADD RES..1
(-5275 1100);
FORCEPROP 1 LAST PART_NUMBER G21796-017
J 0
(-5325 1200);
DISPLAY 0.617021 (-5325 1200);
PAINT BLUE (-5325 1200);
FORCEPROP 1 LASTPIN (-5175 1100) $PN 2
J 0
(-5213 1112);
DISPLAY 0.617021 (-5213 1112);
PAINT ORANGE (-5213 1112);
FORCEPROP 1 LAST TOLERANCE 1%
J 0
(-5225 1025);
DISPLAY 0.617021 (-5225 1025);
PAINT SKYBLUE (-5225 1025);
FORCEPROP 1 LAST LOCATION R1C4
J 0
(-5325 1150);
DISPLAY 0.617021 (-5325 1150);
PAINT AQUA (-5325 1150);
FORCEPROP 1 LASTPIN (-5375 1100) $PN 1
J 0
(-5363 1112);
DISPLAY 0.617021 (-5363 1112);
PAINT ORANGE (-5363 1112);
FORCEPROP 1 LAST VALUE 100.0
J 2
(-5275 1025);
DISPLAY 0.617021 (-5275 1025);
PAINT SKYBLUE (-5275 1025);
FORCEPROP 1 LAST PACK_TYPE 0402
J 0
(-5350 925);
DISPLAY 0.617021 (-5350 925);
PAINT SKYBLUE (-5350 925);
FORCEPROP 1 LAST WATTAGE 1/16W
J 2
(-5275 975);
DISPLAY 0.617021 (-5275 975);
PAINT SKYBLUE (-5275 975);
FORCEPROP 2 LAST SEC 1
J 0
(-5310 1310);
DISPLAY 0.680851 (-5310 1310);
PAINT MONO (-5310 1310);
DISPLAY INVISIBLE (-5310 1310);
FORCEPROP 2 LAST SEC_TYPE 0402
J 0
(-5310 1310);
DISPLAY 1.021277 (-5310 1310);
PAINT ORANGE (-5310 1310);
DISPLAY INVISIBLE (-5310 1310);
FORCEPROP 2 LAST BOM_COST PROC_VRD_VCCIN_CPU0
J 0
(-5325 1250);
PAINT MONO (-5325 1250);
DISPLAY INVISIBLE (-5325 1250);
FORCEPROP 1 LAST PATH I33
J 0
(-5325 1250);
DISPLAY 0.978723 (-5325 1250);
PAINT WHITE (-5325 1250);
DISPLAY INVISIBLE (-5325 1250);
FORCEPROP 2 LAST ROOM PVSA_CPU1_VSENSE_VR
J 0
(-5325 1200);
PAINT ORANGE (-5325 1200);
DISPLAY INVISIBLE (-5325 1200);
FORCEPROP 2 LAST CDS_LOCATION R1C4
J 0
(-5325 1150);
DISPLAY 0.617021 (-5325 1150);
PAINT AQUA (-5325 1150);
DISPLAY INVISIBLE (-5325 1150);
FORCEPROP 2 LAST CDS_LIB mstr_discrete
J 0
(-5275 1100);
PAINT ORANGE (-5275 1100);
DISPLAY INVISIBLE (-5275 1100);
FORCEPROP 1 LAST MATERIAL CHIP
J 0
(-5250 975);
PAINT SKYBLUE (-5250 975);
DISPLAY INVISIBLE (-5250 975);
FORCEADD RES..2
(-5950 1725);
FORCEPROP 1 LAST PACK_TYPE 0402
J 0
(-5910 1550);
DISPLAY 0.617021 (-5910 1550);
PAINT SKYBLUE (-5910 1550);
FORCEPROP 1 LAST PART_NUMBER G21796-026
J 0
(-5910 1600);
DISPLAY 0.617021 (-5910 1600);
PAINT BLUE (-5910 1600);
FORCEPROP 1 LAST MATERIAL EMPTY
J 0
(-5910 1650);
DISPLAY 0.617021 (-5910 1650);
PAINT RED (-5910 1650);
FORCEPROP 1 LAST LOCATION R1C6
J 0
(-5905 1850);
DISPLAY 0.617021 (-5905 1850);
PAINT AQUA (-5905 1850);
FORCEPROP 1 LAST TOLERANCE 1%
J 0
(-5905 1750);
DISPLAY 0.617021 (-5905 1750);
PAINT SKYBLUE (-5905 1750);
FORCEPROP 1 LAST WATTAGE 1/16W
J 0
(-5910 1700);
DISPLAY 0.617021 (-5910 1700);
PAINT SKYBLUE (-5910 1700);
FORCEPROP 1 LASTPIN (-5950 1825) $PN 1
J 0
(-5945 1787);
DISPLAY 0.617021 (-5945 1787);
PAINT ORANGE (-5945 1787);
FORCEPROP 1 LASTPIN (-5950 1625) $PN 2
J 0
(-5945 1635);
DISPLAY 0.617021 (-5945 1635);
PAINT ORANGE (-5945 1635);
FORCEPROP 1 LAST VALUE 1.00K
J 0
(-5905 1800);
DISPLAY 0.617021 (-5905 1800);
PAINT SKYBLUE (-5905 1800);
FORCEPROP 2 LAST SEC_TYPE 0402
J 0
(-5885 1960);
DISPLAY 1.021277 (-5885 1960);
PAINT ORANGE (-5885 1960);
DISPLAY INVISIBLE (-5885 1960);
FORCEPROP 2 LAST SEC 1
J 0
(-5885 1960);
DISPLAY 0.680851 (-5885 1960);
PAINT MONO (-5885 1960);
DISPLAY INVISIBLE (-5885 1960);
FORCEPROP 2 LAST NO_XNET_CONNECTION 1
J 0
(-5900 1950);
PAINT MONO (-5900 1950);
DISPLAY INVISIBLE (-5900 1950);
FORCEPROP 2 LAST BOM_COST PROC_VRD_VCCIN_CPU0
J 0
(-5900 1900);
PAINT MONO (-5900 1900);
DISPLAY INVISIBLE (-5900 1900);
FORCEPROP 1 LAST PATH I34
J 0
(-5900 1900);
DISPLAY 0.978723 (-5900 1900);
PAINT WHITE (-5900 1900);
DISPLAY INVISIBLE (-5900 1900);
FORCEPROP 2 LAST ROOM PVSA_CPU1_VSENSE_VR
J 0
(-5900 1900);
PAINT MONO (-5900 1900);
DISPLAY INVISIBLE (-5900 1900);
FORCEPROP 2 LAST CDS_LOCATION R1C6
J 0
(-5905 1850);
DISPLAY 0.617021 (-5905 1850);
PAINT AQUA (-5905 1850);
DISPLAY INVISIBLE (-5905 1850);
FORCEPROP 2 LAST CDS_LIB mstr_discrete
J 0
(-5950 1725);
PAINT ORANGE (-5950 1725);
DISPLAY INVISIBLE (-5950 1725);
FORCEADD CAP..1
(-6850 3825);
FORCEPROP 1 LAST LOCATION C9N13
J 0
(-6800 3925);
DISPLAY 0.617021 (-6800 3925);
PAINT AQUA (-6800 3925);
FORCEPROP 1 LAST VALUE 10UF
J 0
(-6800 3875);
DISPLAY 0.617021 (-6800 3875);
PAINT SKYBLUE (-6800 3875);
FORCEPROP 1 LASTPIN (-6850 3925) $PN 1
J 0
(-6840 3905);
DISPLAY 0.617021 (-6840 3905);
PAINT ORANGE (-6840 3905);
FORCEPROP 1 LAST VOLTAGE 16V
J 0
(-6800 3825);
DISPLAY 0.617021 (-6800 3825);
PAINT SKYBLUE (-6800 3825);
FORCEPROP 1 LAST TOLERANCE 10%
J 0
(-6800 3775);
DISPLAY 0.617021 (-6800 3775);
PAINT SKYBLUE (-6800 3775);
FORCEPROP 1 LAST PACK_TYPE 0805
J 0
(-6800 3625);
DISPLAY 0.617021 (-6800 3625);
PAINT SKYBLUE (-6800 3625);
FORCEPROP 1 LASTPIN (-6850 3725) $PN 2
J 0
(-6840 3705);
DISPLAY 0.617021 (-6840 3705);
PAINT ORANGE (-6840 3705);
FORCEPROP 1 LAST MATERIAL X6S
J 0
(-6800 3725);
DISPLAY 0.617021 (-6800 3725);
PAINT SKYBLUE (-6800 3725);
FORCEPROP 1 LAST PART_NUMBER C95333-007
J 0
(-6800 3675);
DISPLAY 0.617021 (-6800 3675);
PAINT BLUE (-6800 3675);
FORCEPROP 2 LAST SEC_TYPE 0805
J 0
(-6800 4025);
DISPLAY 1.021277 (-6800 4025);
PAINT ORANGE (-6800 4025);
DISPLAY INVISIBLE (-6800 4025);
FORCEPROP 2 LAST SEC 1
J 0
(-6800 4025);
DISPLAY 0.680851 (-6800 4025);
PAINT MONO (-6800 4025);
DISPLAY INVISIBLE (-6800 4025);
FORCEPROP 2 LAST CDS_LOCATION C9N13
J 0
(-6800 3925);
DISPLAY 0.617021 (-6800 3925);
PAINT AQUA (-6800 3925);
DISPLAY INVISIBLE (-6800 3925);
FORCEPROP 1 LAST PATH I35
J 0
(-6800 3975);
DISPLAY 0.978723 (-6800 3975);
PAINT WHITE (-6800 3975);
DISPLAY INVISIBLE (-6800 3975);
FORCEPROP 2 LAST ROOM PVSA_CPU1_PWR_VR
J 0
(-6800 3975);
DISPLAY 1.361702 (-6800 3975);
PAINT ORANGE (-6800 3975);
DISPLAY INVISIBLE (-6800 3975);
FORCEPROP 2 LAST CDS_LIB mstr_discrete
J 0
(-6850 3825);
PAINT ORANGE (-6850 3825);
DISPLAY INVISIBLE (-6850 3825);
FORCEADD CAP..1
(-7150 3850);
FORCEPROP 1 LAST LOCATION C9N19
J 0
(-7100 3950);
DISPLAY 0.617021 (-7100 3950);
PAINT AQUA (-7100 3950);
FORCEPROP 1 LAST VOLTAGE 16V
J 0
(-7100 3850);
DISPLAY 0.617021 (-7100 3850);
PAINT SKYBLUE (-7100 3850);
FORCEPROP 1 LAST PACK_TYPE 0805
J 0
(-7100 3650);
DISPLAY 0.617021 (-7100 3650);
PAINT SKYBLUE (-7100 3650);
FORCEPROP 1 LAST TOLERANCE 10%
J 0
(-7100 3800);
DISPLAY 0.617021 (-7100 3800);
PAINT SKYBLUE (-7100 3800);
FORCEPROP 1 LAST MATERIAL X6S
J 0
(-7100 3750);
DISPLAY 0.617021 (-7100 3750);
PAINT SKYBLUE (-7100 3750);
FORCEPROP 1 LASTPIN (-7150 3750) $PN 2
J 0
(-7140 3730);
DISPLAY 0.617021 (-7140 3730);
PAINT ORANGE (-7140 3730);
FORCEPROP 1 LAST VALUE 10UF
J 0
(-7100 3900);
DISPLAY 0.617021 (-7100 3900);
PAINT SKYBLUE (-7100 3900);
FORCEPROP 1 LASTPIN (-7150 3950) $PN 1
J 0
(-7140 3930);
DISPLAY 0.617021 (-7140 3930);
PAINT ORANGE (-7140 3930);
FORCEPROP 1 LAST PART_NUMBER C95333-007
J 0
(-7100 3700);
DISPLAY 0.617021 (-7100 3700);
PAINT BLUE (-7100 3700);
FORCEPROP 1 LAST PATH I36
J 0
(-7100 4000);
DISPLAY 0.978723 (-7100 4000);
PAINT WHITE (-7100 4000);
DISPLAY INVISIBLE (-7100 4000);
FORCEPROP 2 LAST ROOM PVSA_CPU1_PWR_VR
J 0
(-7100 4000);
DISPLAY 1.361702 (-7100 4000);
PAINT ORANGE (-7100 4000);
DISPLAY INVISIBLE (-7100 4000);
FORCEPROP 2 LAST SEC_TYPE 0805
J 0
(-7100 4050);
DISPLAY 1.021277 (-7100 4050);
PAINT ORANGE (-7100 4050);
DISPLAY INVISIBLE (-7100 4050);
FORCEPROP 2 LAST SEC 1
J 0
(-7100 4050);
DISPLAY 0.680851 (-7100 4050);
PAINT MONO (-7100 4050);
DISPLAY INVISIBLE (-7100 4050);
FORCEPROP 2 LAST CDS_LOCATION C9N19
J 0
(-7100 3950);
DISPLAY 0.617021 (-7100 3950);
PAINT AQUA (-7100 3950);
DISPLAY INVISIBLE (-7100 3950);
FORCEPROP 2 LAST CDS_LIB mstr_discrete
J 0
(-7150 3850);
PAINT ORANGE (-7150 3850);
DISPLAY INVISIBLE (-7150 3850);
FORCEADD CAP..1
(-7400 3850);
FORCEPROP 1 LAST PART_NUMBER C95333-007
J 0
(-7350 3700);
DISPLAY 0.617021 (-7350 3700);
PAINT BLUE (-7350 3700);
FORCEPROP 1 LAST VOLTAGE 16V
J 0
(-7350 3850);
DISPLAY 0.617021 (-7350 3850);
PAINT SKYBLUE (-7350 3850);
FORCEPROP 1 LAST VALUE 10UF
J 0
(-7350 3900);
DISPLAY 0.617021 (-7350 3900);
PAINT SKYBLUE (-7350 3900);
FORCEPROP 1 LASTPIN (-7400 3950) $PN 1
J 0
(-7390 3930);
DISPLAY 0.617021 (-7390 3930);
PAINT ORANGE (-7390 3930);
FORCEPROP 1 LAST TOLERANCE 10%
J 0
(-7350 3800);
DISPLAY 0.617021 (-7350 3800);
PAINT SKYBLUE (-7350 3800);
FORCEPROP 1 LAST PACK_TYPE 0805
J 0
(-7350 3650);
DISPLAY 0.617021 (-7350 3650);
PAINT SKYBLUE (-7350 3650);
FORCEPROP 1 LAST MATERIAL X6S
J 0
(-7350 3750);
DISPLAY 0.617021 (-7350 3750);
PAINT SKYBLUE (-7350 3750);
FORCEPROP 1 LASTPIN (-7400 3750) $PN 2
J 0
(-7390 3730);
DISPLAY 0.617021 (-7390 3730);
PAINT ORANGE (-7390 3730);
FORCEPROP 1 LAST LOCATION C9N21
J 0
(-7350 3950);
DISPLAY 0.617021 (-7350 3950);
PAINT AQUA (-7350 3950);
FORCEPROP 2 LAST SEC 1
J 0
(-7350 4050);
DISPLAY 0.680851 (-7350 4050);
PAINT MONO (-7350 4050);
DISPLAY INVISIBLE (-7350 4050);
FORCEPROP 2 LAST SEC_TYPE 0805
J 0
(-7350 4050);
DISPLAY 1.021277 (-7350 4050);
PAINT ORANGE (-7350 4050);
DISPLAY INVISIBLE (-7350 4050);
FORCEPROP 1 LAST PATH I38
J 0
(-7350 4000);
DISPLAY 0.978723 (-7350 4000);
PAINT WHITE (-7350 4000);
DISPLAY INVISIBLE (-7350 4000);
FORCEPROP 2 LAST ROOM PVSA_CPU1_PWR_VR
J 0
(-7350 4000);
DISPLAY 1.361702 (-7350 4000);
PAINT ORANGE (-7350 4000);
DISPLAY INVISIBLE (-7350 4000);
FORCEPROP 2 LAST CDS_LOCATION C9N21
J 0
(-7350 3950);
DISPLAY 0.617021 (-7350 3950);
PAINT AQUA (-7350 3950);
DISPLAY INVISIBLE (-7350 3950);
FORCEPROP 2 LAST CDS_LIB mstr_discrete
J 0
(-7400 3850);
PAINT ORANGE (-7400 3850);
DISPLAY INVISIBLE (-7400 3850);
FORCEADD GND..1
(-7400 3350);
FORCEPROP 3 LASTPIN (-7400 3400) SIG_NAME GND\g
J 0
(-7390 3410);
DISPLAY 0.659574 (-7390 3410);
PAINT MONO (-7390 3410);
DISPLAY INVISIBLE (-7390 3410);
FORCEPROP 1 LAST HDL_POWER GND
J 0
(-7400 3500);
DISPLAY 1.723404 (-7400 3500);
PAINT GREEN (-7400 3500);
DISPLAY INVISIBLE (-7400 3500);
FORCEPROP 1 LAST VOLTAGE 0
J 0
(-7400 3350);
PAINT SKYBLUE (-7400 3350);
DISPLAY INVISIBLE (-7400 3350);
FORCEPROP 2 LAST CDS_LIB mstr_symbols
J 0
(-7400 3350);
PAINT ORANGE (-7400 3350);
DISPLAY INVISIBLE (-7400 3350);
FORCEPROP 1 LAST PATH I39
J 0
(-7325 3350);
DISPLAY 0.872340 (-7325 3350);
PAINT AQUA (-7325 3350);
DISPLAY INVISIBLE (-7325 3350);
FORCEPROP 1 LAST SIZE 1B
J 0
(-7325 3300);
DISPLAY 1.723404 (-7325 3300);
PAINT GREEN (-7325 3300);
DISPLAY INVISIBLE (-7325 3300);
FORCEPROP 1 LAST BODY_TYPE PLUMBING
J 0
(-7445 3307);
DISPLAY 0.340426 (-7445 3307);
PAINT GREEN (-7445 3307);
DISPLAY INVISIBLE (-7445 3307);
FORCEPROP 2 LAST BOM_COST PROC_VRD_VCCIN_CPU0
J 0
(-7775 3425);
DISPLAY 1.446809 (-7775 3425);
PAINT MONO (-7775 3425);
DISPLAY INVISIBLE (-7775 3425);
FORCEPROP 2 LAST ROOM PVSA_CPU1_PWR_VR
J 0
(-7950 3425);
DISPLAY 1.936170 (-7950 3425);
PAINT ORANGE (-7950 3425);
DISPLAY INVISIBLE (-7950 3425);
FORCEADD OFFPAGE..1
(-7400 1975);
FORCEPROP 2 LAST $XR0 206 
J 0
(-7652 1975);
DISPLAY 0.638298 (-7652 1975);
PAINT MONO (-7652 1975);
FORCEPROP 2 LAST ROOM PVSA_CPU1_VSENSE_VR
J 0
(-7925 2050);
PAINT ORANGE (-7925 2050);
DISPLAY INVISIBLE (-7925 2050);
FORCEPROP 2 LAST BOM_COST PROC_VRD_VCCIN_CPU0
J 0
(-7600 2025);
PAINT MONO (-7600 2025);
DISPLAY INVISIBLE (-7600 2025);
FORCEPROP 2 LAST PATH I40
J 0
(-7635 2010);
DISPLAY 1.021277 (-7635 2010);
PAINT ORANGE (-7635 2010);
DISPLAY INVISIBLE (-7635 2010);
FORCEPROP 1 LAST OFFPAGE TRUE
J 0
(-7075 1850);
DISPLAY 0.893617 (-7075 1850);
PAINT GREEN (-7075 1850);
DISPLAY INVISIBLE (-7075 1850);
FORCEPROP 2 LAST CDS_LIB mstr_standard
J 0
(-7400 1975);
PAINT ORANGE (-7400 1975);
DISPLAY INVISIBLE (-7400 1975);
FORCEPROP 1 LAST COMMENT_BODY TRUE
J 0
(-7275 1875);
DISPLAY 0.893617 (-7275 1875);
PAINT GREEN (-7275 1875);
DISPLAY INVISIBLE (-7275 1875);
FORCEADD OFFPAGE..1
(-7425 1500);
FORCEPROP 2 LAST $XR0 206 
J 0
(-7677 1500);
DISPLAY 0.638298 (-7677 1500);
PAINT MONO (-7677 1500);
FORCEPROP 1 LAST OFFPAGE TRUE
J 0
(-7100 1375);
DISPLAY 0.893617 (-7100 1375);
PAINT GREEN (-7100 1375);
DISPLAY INVISIBLE (-7100 1375);
FORCEPROP 2 LAST BOM_COST PROC_VRD_VCCIN_CPU0
J 0
(-7625 1550);
PAINT MONO (-7625 1550);
DISPLAY INVISIBLE (-7625 1550);
FORCEPROP 2 LAST CDS_LIB mstr_standard
J 0
(-7425 1500);
PAINT ORANGE (-7425 1500);
DISPLAY INVISIBLE (-7425 1500);
FORCEPROP 2 LAST PATH I41
J 0
(-7660 1535);
DISPLAY 1.021277 (-7660 1535);
PAINT ORANGE (-7660 1535);
DISPLAY INVISIBLE (-7660 1535);
FORCEPROP 1 LAST COMMENT_BODY TRUE
J 0
(-7300 1400);
DISPLAY 0.893617 (-7300 1400);
PAINT GREEN (-7300 1400);
DISPLAY INVISIBLE (-7300 1400);
FORCEPROP 2 LAST ROOM PVSA_CPU1_VSENSE_VR
J 0
(-7950 1575);
PAINT ORANGE (-7950 1575);
DISPLAY INVISIBLE (-7950 1575);
FORCEADD P5V_STBY..1
(-4825 4575);
FORCEPROP 3 LASTPIN (-4825 4525) SIG_NAME P5V_STBY\g
J 0
(-4815 4535);
DISPLAY 0.659574 (-4815 4535);
PAINT MONO (-4815 4535);
DISPLAY INVISIBLE (-4815 4535);
FORCEPROP 1 LAST SIZE 1B
J 0
(-4780 4597);
DISPLAY 0.340426 (-4780 4597);
PAINT GREEN (-4780 4597);
DISPLAY INVISIBLE (-4780 4597);
FORCEPROP 2 LAST CDS_LIB mstr_symbols
J 0
(-4825 4575);
PAINT ORANGE (-4825 4575);
DISPLAY INVISIBLE (-4825 4575);
FORCEPROP 1 LAST PATH I42
J 0
(-4780 4577);
DISPLAY 0.340426 (-4780 4577);
PAINT GREEN (-4780 4577);
DISPLAY INVISIBLE (-4780 4577);
FORCEPROP 1 LAST VOLTAGE 5.0V
J 0
(-4870 4532);
DISPLAY 0.340426 (-4870 4532);
PAINT SKYBLUE (-4870 4532);
DISPLAY INVISIBLE (-4870 4532);
FORCEPROP 1 LAST BODY_TYPE PLUMBING
J 0
(-4870 4532);
DISPLAY 0.340426 (-4870 4532);
PAINT GREEN (-4870 4532);
DISPLAY INVISIBLE (-4870 4532);
FORCEPROP 1 LAST HDL_POWER P5V_STBY
J 0
(-5125 4450);
DISPLAY 0.872340 (-5125 4450);
PAINT ORANGE (-5125 4450);
DISPLAY INVISIBLE (-5125 4450);
FORCEADD CAP_A..1
(-1050 3050);
FORCEPROP 1 LAST LOCATION C9N22
J 0
(-1000 3150);
DISPLAY 0.617021 (-1000 3150);
PAINT AQUA (-1000 3150);
FORCEPROP 1 LAST VALUE 22.0UF
J 0
(-1000 3100);
DISPLAY 0.617021 (-1000 3100);
PAINT SKYBLUE (-1000 3100);
FORCEPROP 1 LAST VOLTAGE 4V
J 0
(-1000 3050);
DISPLAY 0.617021 (-1000 3050);
PAINT SKYBLUE (-1000 3050);
FORCEPROP 1 LAST MATERIAL X6S
J 0
(-1000 2950);
DISPLAY 0.617021 (-1000 2950);
PAINT SKYBLUE (-1000 2950);
FORCEPROP 1 LAST PACK_TYPE 0603V
J 0
(-1000 2850);
DISPLAY 0.617021 (-1000 2850);
PAINT SKYBLUE (-1000 2850);
FORCEPROP 1 LAST TOLERANCE 20%
J 0
(-1000 3000);
DISPLAY 0.617021 (-1000 3000);
PAINT SKYBLUE (-1000 3000);
FORCEPROP 1 LAST PART_NUMBER E15431-004
J 0
(-1000 2900);
DISPLAY 0.617021 (-1000 2900);
PAINT BLUE (-1000 2900);
FORCEPROP 1 LASTPIN (-1050 3150) $PN 1
J 0
(-1040 3130);
DISPLAY 0.617021 (-1040 3130);
PAINT ORANGE (-1040 3130);
FORCEPROP 1 LASTPIN (-1050 2950) $PN 2
J 0
(-1040 2930);
DISPLAY 0.617021 (-1040 2930);
PAINT ORANGE (-1040 2930);
FORCEPROP 2 LAST CDS_LOCATION C9N22
J 0
(-1000 3150);
DISPLAY 0.617021 (-1000 3150);
PAINT AQUA (-1000 3150);
DISPLAY INVISIBLE (-1000 3150);
FORCEPROP 2 LAST CDS_SEC 1
J 0
(-1000 3200);
PAINT ORANGE (-1000 3200);
DISPLAY INVISIBLE (-1000 3200);
FORCEPROP 2 LAST SEC_TYPE 0603V
J 0
(-1000 3250);
DISPLAY 1.021277 (-1000 3250);
PAINT ORANGE (-1000 3250);
DISPLAY INVISIBLE (-1000 3250);
FORCEPROP 2 LAST SEC 1
J 0
(-1000 3250);
DISPLAY 0.680851 (-1000 3250);
PAINT MONO (-1000 3250);
DISPLAY INVISIBLE (-1000 3250);
FORCEPROP 1 LAST PATH I44
J 0
(-1000 3200);
DISPLAY 0.978723 (-1000 3200);
PAINT WHITE (-1000 3200);
DISPLAY INVISIBLE (-1000 3200);
FORCEPROP 2 LAST CDS_LIB dev_discrete
J 0
(-1050 3050);
PAINT ORANGE (-1050 3050);
DISPLAY INVISIBLE (-1050 3050);
FORCEADD RES..2
(-625 3075);
FORCEPROP 1 LAST LOCATION R9N4
J 0
(-580 3200);
DISPLAY 0.617021 (-580 3200);
PAINT AQUA (-580 3200);
FORCEPROP 1 LAST VALUE 51.1
J 0
(-580 3150);
DISPLAY 0.617021 (-580 3150);
PAINT SKYBLUE (-580 3150);
FORCEPROP 1 LAST TOLERANCE 1.0%
J 0
(-580 3100);
DISPLAY 0.617021 (-580 3100);
PAINT SKYBLUE (-580 3100);
FORCEPROP 1 LAST WATTAGE 1/16W
J 0
(-585 3050);
DISPLAY 0.617021 (-585 3050);
PAINT SKYBLUE (-585 3050);
FORCEPROP 1 LAST MATERIAL CHIP
J 0
(-585 3000);
DISPLAY 0.617021 (-585 3000);
PAINT SKYBLUE (-585 3000);
FORCEPROP 1 LAST PACK_TYPE 0402
J 0
(-585 2900);
DISPLAY 0.617021 (-585 2900);
PAINT SKYBLUE (-585 2900);
FORCEPROP 1 LAST PART_NUMBER G21796-208
J 0
(-585 2950);
DISPLAY 0.617021 (-585 2950);
PAINT BLUE (-585 2950);
FORCEPROP 2 LAST CDS_SEC 1
J 0
(-575 3300);
DISPLAY 1.021277 (-575 3300);
PAINT ORANGE (-575 3300);
DISPLAY INVISIBLE (-575 3300);
FORCEPROP 2 LAST $SEC 1
J 0
(-575 3300);
DISPLAY 0.680851 (-575 3300);
PAINT MONO (-575 3300);
DISPLAY INVISIBLE (-575 3300);
FORCEPROP 1 LAST PATH I45
J 0
(-575 3250);
DISPLAY 0.978723 (-575 3250);
PAINT WHITE (-575 3250);
DISPLAY INVISIBLE (-575 3250);
FORCEPROP 2 LAST CDS_LOCATION R9N4
J 0
(-580 3200);
DISPLAY 0.617021 (-580 3200);
PAINT AQUA (-580 3200);
DISPLAY INVISIBLE (-580 3200);
FORCEPROP 2 LAST CDS_LIB mstr_discrete
J 0
(-625 3075);
PAINT ORANGE (-625 3075);
DISPLAY INVISIBLE (-625 3075);
FORCEPROP 1 LASTPIN (-625 3175) $PN 1
J 0
(-620 3137);
DISPLAY 0.787234 (-620 3137);
PAINT ORANGE (-620 3137);
DISPLAY INVISIBLE (-620 3137);
FORCEPROP 1 LASTPIN (-625 2975) $PN 2
J 0
(-620 2985);
DISPLAY 0.787234 (-620 2985);
PAINT ORANGE (-620 2985);
DISPLAY INVISIBLE (-620 2985);
FORCEADD PVSA_CPU1..1
(-4575 2500);
FORCEPROP 3 LASTPIN (-4575 2450) SIG_NAME PVSA_CPU1\g
J 0
(-4565 2460);
DISPLAY 0.659574 (-4565 2460);
PAINT MONO (-4565 2460);
DISPLAY INVISIBLE (-4565 2460);
FORCEPROP 1 LAST HDL_POWER PVSA_CPU1
J 1
(-4575 2550);
DISPLAY 0.872340 (-4575 2550);
PAINT GREEN (-4575 2550);
DISPLAY INVISIBLE (-4575 2550);
FORCEPROP 2 LAST ROOM PVSA_CPU1_PWR_VR
J 0
(-4575 2600);
DISPLAY 1.936170 (-4575 2600);
PAINT ORANGE (-4575 2600);
DISPLAY INVISIBLE (-4575 2600);
FORCEPROP 1 LAST PATH I46
J 0
(-4525 2525);
DISPLAY 0.872340 (-4525 2525);
PAINT AQUA (-4525 2525);
DISPLAY INVISIBLE (-4525 2525);
FORCEPROP 2 LAST BOM_COST PROC_VRD_VCCIN_CPU0
J 0
(-4575 2600);
DISPLAY 1.446809 (-4575 2600);
PAINT MONO (-4575 2600);
DISPLAY INVISIBLE (-4575 2600);
FORCEPROP 2 LAST CDS_LIB mstr_symbols
J 0
(-4575 2500);
PAINT ORANGE (-4575 2500);
DISPLAY INVISIBLE (-4575 2500);
FORCEPROP 1 LAST BODY_TYPE PLUMBING
J 0
(-4620 2457);
DISPLAY 0.340426 (-4620 2457);
PAINT GREEN (-4620 2457);
DISPLAY INVISIBLE (-4620 2457);
FORCEPROP 1 LAST VOLTAGE 1.1V
J 0
(-4620 2457);
DISPLAY 0.340426 (-4620 2457);
PAINT SKYBLUE (-4620 2457);
DISPLAY INVISIBLE (-4620 2457);
FORCEADD PVSA_CPU1..1
(-1325 1700);
FORCEPROP 3 LASTPIN (-1325 1650) SIG_NAME PVSA_CPU1\g
J 0
(-1315 1660);
DISPLAY 0.659574 (-1315 1660);
PAINT MONO (-1315 1660);
DISPLAY INVISIBLE (-1315 1660);
FORCEPROP 1 LAST PATH I47
J 0
(-1275 1725);
DISPLAY 0.872340 (-1275 1725);
PAINT AQUA (-1275 1725);
DISPLAY INVISIBLE (-1275 1725);
FORCEPROP 2 LAST BOM_COST PROC_VRD_VCCIN_CPU0
J 0
(-1325 1800);
DISPLAY 1.446809 (-1325 1800);
PAINT MONO (-1325 1800);
DISPLAY INVISIBLE (-1325 1800);
FORCEPROP 2 LAST ROOM PVSA_CPU1_PWR_VR
J 0
(-1325 1800);
DISPLAY 1.936170 (-1325 1800);
PAINT ORANGE (-1325 1800);
DISPLAY INVISIBLE (-1325 1800);
FORCEPROP 2 LAST CDS_LIB mstr_symbols
J 0
(-1325 1700);
PAINT ORANGE (-1325 1700);
DISPLAY INVISIBLE (-1325 1700);
FORCEPROP 1 LAST HDL_POWER PVSA_CPU1
J 1
(-1325 1750);
DISPLAY 0.872340 (-1325 1750);
PAINT GREEN (-1325 1750);
DISPLAY INVISIBLE (-1325 1750);
FORCEPROP 1 LAST VOLTAGE 1.1V
J 0
(-1370 1657);
DISPLAY 0.340426 (-1370 1657);
PAINT SKYBLUE (-1370 1657);
DISPLAY INVISIBLE (-1370 1657);
FORCEPROP 1 LAST BODY_TYPE PLUMBING
J 0
(-1370 1657);
DISPLAY 0.340426 (-1370 1657);
PAINT GREEN (-1370 1657);
DISPLAY INVISIBLE (-1370 1657);
FORCEADD OFFPAGE..1
(-7100 3500);
FORCEPROP 2 LAST $XR0 206 
J 0
(-7352 3500);
DISPLAY 0.638298 (-7352 3500);
PAINT MONO (-7352 3500);
FORCEPROP 1 LAST OFFPAGE TRUE
J 0
(-6775 3375);
DISPLAY 1.680851 (-6775 3375);
PAINT GREEN (-6775 3375);
DISPLAY INVISIBLE (-6775 3375);
FORCEPROP 1 LAST COMMENT_BODY TRUE
J 0
(-6975 3400);
DISPLAY 1.680851 (-6975 3400);
PAINT GREEN (-6975 3400);
DISPLAY INVISIBLE (-6975 3400);
FORCEPROP 2 LAST PATH I50
J 0
(-7050 3575);
DISPLAY 1.021277 (-7050 3575);
PAINT ORANGE (-7050 3575);
DISPLAY INVISIBLE (-7050 3575);
FORCEPROP 2 LAST CDS_LIB mstr_standard
J 0
(-7100 3500);
PAINT ORANGE (-7100 3500);
DISPLAY INVISIBLE (-7100 3500);
FORCEPROP 2 LAST ROOM PVSA_CPU1_PWR_VR
J 0
(-7500 3575);
DISPLAY 1.936170 (-7500 3575);
PAINT ORANGE (-7500 3575);
DISPLAY INVISIBLE (-7500 3575);
FORCEPROP 2 LAST BOM_COST PROC_VRD_VCCIN_CPU0
J 0
(-7350 3550);
DISPLAY 1.446809 (-7350 3550);
PAINT MONO (-7350 3550);
DISPLAY INVISIBLE (-7350 3550);
FORCEADD IR354XX..1
(-3725 3600);
FORCEPROP 1 LAST VALUE IR35412
J 1
(-3725 4225);
DISPLAY 0.617021 (-3725 4225);
PAINT SKYBLUE (-3725 4225);
FORCEPROP 2 LASTPIN (-3225 4150) $PN 38
J 0
(-3215 4160);
DISPLAY 0.617021 (-3215 4160);
PAINT ORANGE (-3215 4160);
FORCEPROP 2 LASTPIN (-3225 3650) $PN 36
J 0
(-3215 3660);
DISPLAY 0.617021 (-3215 3660);
PAINT ORANGE (-3215 3660);
FORCEPROP 2 LASTPIN (-3225 3950) $PN 37
J 0
(-3215 3960);
DISPLAY 0.617021 (-3215 3960);
PAINT ORANGE (-3215 3960);
FORCEPROP 2 LASTPIN (-3225 3900) $PN 31
J 0
(-3215 3910);
DISPLAY 0.617021 (-3215 3910);
PAINT ORANGE (-3215 3910);
FORCEPROP 2 LASTPIN (-3225 3300) $PN 10
J 0
(-3215 3310);
DISPLAY 0.617021 (-3215 3310);
PAINT ORANGE (-3215 3310);
FORCEPROP 2 LASTPIN (-3225 3150) $PN 40
J 0
(-3215 3160);
DISPLAY 0.617021 (-3215 3160);
PAINT ORANGE (-3215 3160);
FORCEPROP 2 LASTPIN (-3225 3100) $PN 7
J 0
(-3215 3110);
DISPLAY 0.617021 (-3215 3110);
PAINT ORANGE (-3215 3110);
FORCEPROP 2 LASTPIN (-3225 3200) $PN 2
J 0
(-3215 3210);
DISPLAY 0.617021 (-3215 3210);
PAINT ORANGE (-3215 3210);
FORCEPROP 2 LASTPIN (-3225 3050) $PN 5
J 0
(-3215 3060);
DISPLAY 0.617021 (-3215 3060);
PAINT ORANGE (-3215 3060);
FORCEPROP 1 LAST LOCATION EU1C1
J 0
(-4175 4400);
DISPLAY 0.617021 (-4175 4400);
PAINT AQUA (-4175 4400);
FORCEPROP 1 LAST MATERIAL IC
J 0
(-4175 4350);
DISPLAY 0.617021 (-4175 4350);
PAINT SKYBLUE (-4175 4350);
FORCEPROP 2 LASTPIN (-4225 4100) $PN 30
J 2
(-4235 4110);
DISPLAY 0.617021 (-4235 4110);
PAINT ORANGE (-4235 4110);
FORCEPROP 2 LASTPIN (-4225 4150) $PN 3
J 2
(-4235 4160);
DISPLAY 0.617021 (-4235 4160);
PAINT ORANGE (-4235 4160);
FORCEPROP 2 LASTPIN (-4225 3950) $PN 4
J 2
(-4235 3960);
DISPLAY 0.617021 (-4235 3960);
PAINT ORANGE (-4235 3960);
FORCEPROP 2 LASTPIN (-4225 4050) $PN 25
J 2
(-4235 4060);
DISPLAY 0.617021 (-4235 4060);
PAINT ORANGE (-4235 4060);
FORCEPROP 2 LASTPIN (-4225 3850) $PN 35
J 2
(-4235 3860);
DISPLAY 0.617021 (-4235 3860);
PAINT ORANGE (-4235 3860);
FORCEPROP 2 LASTPIN (-4225 3600) $PN 6
J 2
(-4235 3610);
DISPLAY 0.617021 (-4235 3610);
PAINT ORANGE (-4235 3610);
FORCEPROP 2 LASTPIN (-4225 3650) $PN 41
J 2
(-4235 3660);
DISPLAY 0.617021 (-4235 3660);
PAINT ORANGE (-4235 3660);
FORCEPROP 2 LASTPIN (-4225 3750) $PN 1
J 2
(-4235 3760);
DISPLAY 0.617021 (-4235 3760);
PAINT ORANGE (-4235 3760);
FORCEPROP 2 LASTPIN (-4225 3300) $PN 33
J 2
(-4235 3310);
DISPLAY 0.617021 (-4235 3310);
PAINT ORANGE (-4235 3310);
FORCEPROP 2 LASTPIN (-4225 3250) $PN 32
J 2
(-4235 3260);
DISPLAY 0.617021 (-4235 3260);
PAINT ORANGE (-4235 3260);
FORCEPROP 2 LASTPIN (-4225 3400) $PN 39
J 2
(-4235 3410);
DISPLAY 0.617021 (-4235 3410);
PAINT ORANGE (-4235 3410);
FORCEPROP 2 LASTPIN (-4225 3500) $PN 34
J 2
(-4235 3510);
DISPLAY 0.617021 (-4235 3510);
PAINT ORANGE (-4235 3510);
FORCEPROP 1 LAST PART_NUMBER H73684-001
J 0
(-4100 2900);
DISPLAY 0.617021 (-4100 2900);
PAINT BLUE (-4100 2900);
FORCEPROP 1 LAST PATH I51
J 0
(-3725 4350);
PAINT GREEN (-3725 4350);
DISPLAY INVISIBLE (-3725 4350);
FORCEPROP 2 LAST CDS_LIB mstr_discrete
J 0
(-3725 3600);
PAINT ORANGE (-3725 3600);
DISPLAY INVISIBLE (-3725 3600);
FORCEPROP 1 LAST PACK_TYPE SM
J 0
(-4175 4450);
PAINT SKYBLUE (-4175 4450);
DISPLAY INVISIBLE (-4175 4450);
FORCEPROP 2 LAST SEC_TYPE SM
J 0
(-4175 4450);
DISPLAY 1.021277 (-4175 4450);
PAINT ORANGE (-4175 4450);
DISPLAY INVISIBLE (-4175 4450);
FORCEPROP 2 LAST SEC 1
J 0
(-4175 4450);
DISPLAY 0.680851 (-4175 4450);
PAINT MONO (-4175 4450);
DISPLAY INVISIBLE (-4175 4450);
FORCEPROP 2 LAST CDS_LOCATION EU1C1
J 0
(-4175 4400);
PAINT GREEN (-4175 4400);
DISPLAY INVISIBLE (-4175 4400);
FORCEADD RES..2
(-1450 3775);
FORCEPROP 1 LAST MATERIAL EMPTY
J 0
(-1410 3700);
DISPLAY 0.617021 (-1410 3700);
PAINT RED (-1410 3700);
FORCEPROP 1 LAST LOCATION R1C37
J 0
(-1405 3900);
DISPLAY 0.617021 (-1405 3900);
PAINT AQUA (-1405 3900);
FORCEPROP 1 LAST PART_NUMBER G21796-187
J 0
(-1410 3650);
DISPLAY 0.617021 (-1410 3650);
PAINT BLUE (-1410 3650);
FORCEPROP 1 LAST VALUE 68.1K
J 0
(-1405 3850);
DISPLAY 0.617021 (-1405 3850);
PAINT SKYBLUE (-1405 3850);
FORCEPROP 1 LAST WATTAGE 1/16W
J 0
(-1410 3750);
DISPLAY 0.617021 (-1410 3750);
PAINT SKYBLUE (-1410 3750);
FORCEPROP 1 LASTPIN (-1450 3875) $PN 1
J 0
(-1445 3837);
DISPLAY 0.617021 (-1445 3837);
PAINT ORANGE (-1445 3837);
FORCEPROP 1 LAST TOLERANCE 1%
J 0
(-1405 3800);
DISPLAY 0.617021 (-1405 3800);
PAINT SKYBLUE (-1405 3800);
FORCEPROP 1 LAST PACK_TYPE 0402
J 0
(-1410 3600);
DISPLAY 0.617021 (-1410 3600);
PAINT SKYBLUE (-1410 3600);
FORCEPROP 1 LASTPIN (-1450 3675) $PN 2
J 0
(-1445 3685);
DISPLAY 0.617021 (-1445 3685);
PAINT ORANGE (-1445 3685);
FORCEPROP 1 LAST PATH I52
J 0
(-1400 3950);
DISPLAY 0.978723 (-1400 3950);
PAINT WHITE (-1400 3950);
DISPLAY INVISIBLE (-1400 3950);
FORCEPROP 2 LAST $SEC 1
J 0
(-1400 4000);
PAINT MONO (-1400 4000);
DISPLAY INVISIBLE (-1400 4000);
FORCEPROP 2 LAST CDS_SEC 1
J 0
(-1400 4000);
PAINT MONO (-1400 4000);
DISPLAY INVISIBLE (-1400 4000);
FORCEPROP 2 LAST CDS_LIB mstr_discrete
J 0
(-1450 3775);
PAINT ORANGE (-1450 3775);
DISPLAY INVISIBLE (-1450 3775);
FORCEADD GND..1
(-1450 3525);
FORCEPROP 3 LASTPIN (-1450 3575) SIG_NAME GND\g
J 0
(-1440 3585);
DISPLAY 0.659574 (-1440 3585);
PAINT MONO (-1440 3585);
DISPLAY INVISIBLE (-1440 3585);
FORCEPROP 1 LAST HDL_POWER GND
J 0
(-1450 3675);
DISPLAY 1.723404 (-1450 3675);
PAINT GREEN (-1450 3675);
DISPLAY INVISIBLE (-1450 3675);
FORCEPROP 1 LAST VOLTAGE 0
J 0
(-1450 3525);
PAINT SKYBLUE (-1450 3525);
DISPLAY INVISIBLE (-1450 3525);
FORCEPROP 1 LAST SIZE 1B
J 0
(-1375 3475);
DISPLAY 1.723404 (-1375 3475);
PAINT GREEN (-1375 3475);
DISPLAY INVISIBLE (-1375 3475);
FORCEPROP 2 LAST CDS_LIB mstr_symbols
J 0
(-1450 3525);
PAINT ORANGE (-1450 3525);
DISPLAY INVISIBLE (-1450 3525);
FORCEPROP 1 LAST BODY_TYPE PLUMBING
J 0
(-1495 3482);
DISPLAY 0.340426 (-1495 3482);
PAINT GREEN (-1495 3482);
DISPLAY INVISIBLE (-1495 3482);
FORCEPROP 1 LAST PATH I53
J 0
(-1375 3525);
DISPLAY 0.872340 (-1375 3525);
PAINT AQUA (-1375 3525);
DISPLAY INVISIBLE (-1375 3525);
FORCEPROP 2 LAST BOM_COST PROC_VRD_VCCIN_CPU0
J 0
(-1825 3600);
DISPLAY 1.446809 (-1825 3600);
PAINT MONO (-1825 3600);
DISPLAY INVISIBLE (-1825 3600);
FORCEPROP 2 LAST ROOM PVSA_CPU1_PWR_VR
J 0
(-2000 3600);
DISPLAY 1.936170 (-2000 3600);
PAINT ORANGE (-2000 3600);
DISPLAY INVISIBLE (-2000 3600);
FORCEADD GND..1
(-4450 2850);
FORCEPROP 3 LASTPIN (-4450 2900) SIG_NAME GND\g
J 0
(-4440 2910);
DISPLAY 0.659574 (-4440 2910);
PAINT MONO (-4440 2910);
DISPLAY INVISIBLE (-4440 2910);
FORCEPROP 2 LAST CDS_LIB mstr_symbols
J 0
(-4450 2850);
PAINT MONO (-4450 2850);
DISPLAY INVISIBLE (-4450 2850);
FORCEPROP 1 LAST PATH I54
J 0
(-4375 2850);
DISPLAY 0.872340 (-4375 2850);
PAINT AQUA (-4375 2850);
DISPLAY INVISIBLE (-4375 2850);
FORCEPROP 1 LAST HDL_POWER GND
J 0
(-4450 3000);
DISPLAY 1.723404 (-4450 3000);
PAINT GREEN (-4450 3000);
DISPLAY INVISIBLE (-4450 3000);
FORCEPROP 1 LAST VOLTAGE 0
J 0
(-4450 2850);
PAINT SKYBLUE (-4450 2850);
DISPLAY INVISIBLE (-4450 2850);
FORCEPROP 1 LAST SIZE 1B
J 0
(-4375 2800);
DISPLAY 1.723404 (-4375 2800);
PAINT GREEN (-4375 2800);
DISPLAY INVISIBLE (-4375 2800);
FORCEPROP 2 LAST BOM_COST PROC_VRD_VCCIN_CPU0
J 0
(-4825 2925);
DISPLAY 1.446809 (-4825 2925);
PAINT MONO (-4825 2925);
DISPLAY INVISIBLE (-4825 2925);
FORCEPROP 2 LAST ROOM PVCCIN_CPU0_PWR_VR
J 0
(-5000 2925);
DISPLAY 1.936170 (-5000 2925);
PAINT ORANGE (-5000 2925);
DISPLAY INVISIBLE (-5000 2925);
FORCEPROP 1 LAST BODY_TYPE PLUMBING
J 0
(-4495 2807);
DISPLAY 0.340426 (-4495 2807);
PAINT GREEN (-4495 2807);
DISPLAY INVISIBLE (-4495 2807);
FORCEADD CAP_A..1
(-4450 3100);
FORCEPROP 1 LAST LOCATION CT57
J 0
(-4450 3175);
DISPLAY 0.617021 (-4450 3175);
PAINT AQUA (-4450 3175);
FORCEPROP 1 LAST VALUE 0.1UF
J 0
(-4400 3150);
DISPLAY 0.617021 (-4400 3150);
PAINT SKYBLUE (-4400 3150);
FORCEPROP 1 LAST VOLTAGE 16V
J 0
(-4400 3100);
DISPLAY 0.617021 (-4400 3100);
PAINT SKYBLUE (-4400 3100);
FORCEPROP 1 LAST PACK_TYPE 0402V
J 0
(-4400 2900);
DISPLAY 0.617021 (-4400 2900);
PAINT SKYBLUE (-4400 2900);
FORCEPROP 1 LAST PART_NUMBER A36096-030
J 0
(-4400 2950);
DISPLAY 0.617021 (-4400 2950);
PAINT BLUE (-4400 2950);
FORCEPROP 1 LAST MATERIAL X7R
J 0
(-4400 3000);
DISPLAY 0.617021 (-4400 3000);
PAINT SKYBLUE (-4400 3000);
FORCEPROP 1 LAST TOLERANCE 10%
J 0
(-4400 3050);
DISPLAY 0.617021 (-4400 3050);
PAINT SKYBLUE (-4400 3050);
FORCEPROP 0 LAST STATUS NOPOP
J 0
(-4700 3050);
DISPLAY 1.021277 (-4700 3050);
PAINT ORANGE (-4700 3050);
FORCEPROP 1 LASTPIN (-4450 3000) $PN 2
J 0
(-4440 2980);
DISPLAY 0.787234 (-4440 2980);
PAINT ORANGE (-4440 2980);
DISPLAY INVISIBLE (-4440 2980);
FORCEPROP 1 LASTPIN (-4450 3200) $PN 1
J 0
(-4440 3180);
DISPLAY 0.787234 (-4440 3180);
PAINT ORANGE (-4440 3180);
DISPLAY INVISIBLE (-4440 3180);
FORCEPROP 2 LAST CDS_LIB dev_discrete
J 0
(-4450 3100);
PAINT MONO (-4450 3100);
DISPLAY INVISIBLE (-4450 3100);
FORCEPROP 1 LAST PATH I55
J 0
(-4400 3250);
DISPLAY 0.978723 (-4400 3250);
PAINT WHITE (-4400 3250);
DISPLAY INVISIBLE (-4400 3250);
FORCEPROP 2 LAST ROOM PVCCIN_CPU0_PWR_VR
J 0
(-4400 3250);
DISPLAY 1.361702 (-4400 3250);
PAINT ORANGE (-4400 3250);
DISPLAY INVISIBLE (-4400 3250);
FORCEADD SC2K2P50V3KX-GP..1
(-2500 3125);
FORCEPROP 1 LAST LOCATION CT56
J 0
(-2475 3155);
DISPLAY 0.617021 (-2475 3155);
PAINT GREEN (-2475 3155);
FORCEPROP 0 LAST STATUS NOPOP
J 0
(-2475 3200);
DISPLAY 1.021277 (-2475 3200);
PAINT ORANGE (-2475 3200);
FORCEPROP 1 LAST VALUE SC2K2P50V3KX-GP
J 0
(-2475 3075);
DISPLAY 0.617021 (-2475 3075);
PAINT GREEN (-2475 3075);
FORCEPROP 2 LAST CDS_LIB w_hdl
J 0
(-2500 3125);
PAINT MONO (-2500 3125);
DISPLAY INVISIBLE (-2500 3125);
FORCEPROP 1 LAST PATH I57
J 0
(-2500 3125);
DISPLAY 0.617021 (-2500 3125);
PAINT GREEN (-2500 3125);
DISPLAY INVISIBLE (-2500 3125);
FORCEPROP 1 LAST CDS_LMAN_SYM_OUTLINE -50,25,50,-25
J 0
(-2500 3125);
DISPLAY 0.468085 (-2500 3125);
PAINT GREEN (-2500 3125);
DISPLAY INVISIBLE (-2500 3125);
FORCEPROP 1 LAST PART_NUMBER 78.22224.2BL
J 0
(-2500 3125);
DISPLAY 0.617021 (-2500 3125);
PAINT GREEN (-2500 3125);
DISPLAY INVISIBLE (-2500 3125);
FORCEPROP 1 LAST PACK_TYPE SMD-BCG6
J 0
(-2500 3125);
DISPLAY 0.617021 (-2500 3125);
PAINT GREEN (-2500 3125);
DISPLAY INVISIBLE (-2500 3125);
FORCEADD GND..1
(-2500 2600);
FORCEPROP 3 LASTPIN (-2500 2650) SIG_NAME GND\g
J 0
(-2490 2660);
DISPLAY 0.659574 (-2490 2660);
PAINT MONO (-2490 2660);
DISPLAY INVISIBLE (-2490 2660);
FORCEPROP 2 LAST CDS_LIB mstr_symbols
J 0
(-2500 2600);
PAINT MONO (-2500 2600);
DISPLAY INVISIBLE (-2500 2600);
FORCEPROP 1 LAST PATH I58
J 0
(-2425 2600);
DISPLAY 0.872340 (-2425 2600);
PAINT AQUA (-2425 2600);
DISPLAY INVISIBLE (-2425 2600);
FORCEPROP 2 LAST ROOM PVCCIN_CPU0_PWR_VR
J 0
(-3050 2675);
DISPLAY 1.936170 (-3050 2675);
PAINT ORANGE (-3050 2675);
DISPLAY INVISIBLE (-3050 2675);
FORCEPROP 2 LAST BOM_COST PROC_VRD_VCCIN_CPU0
J 0
(-2875 2675);
DISPLAY 1.446809 (-2875 2675);
PAINT MONO (-2875 2675);
DISPLAY INVISIBLE (-2875 2675);
FORCEPROP 1 LAST BODY_TYPE PLUMBING
J 0
(-2545 2557);
DISPLAY 0.340426 (-2545 2557);
PAINT GREEN (-2545 2557);
DISPLAY INVISIBLE (-2545 2557);
FORCEPROP 1 LAST VOLTAGE 0
J 0
(-2500 2600);
PAINT SKYBLUE (-2500 2600);
DISPLAY INVISIBLE (-2500 2600);
FORCEPROP 1 LAST SIZE 1B
J 0
(-2425 2550);
DISPLAY 1.723404 (-2425 2550);
PAINT GREEN (-2425 2550);
DISPLAY INVISIBLE (-2425 2550);
FORCEPROP 1 LAST HDL_POWER GND
J 0
(-2500 2750);
DISPLAY 1.723404 (-2500 2750);
PAINT GREEN (-2500 2750);
DISPLAY INVISIBLE (-2500 2750);
FORCEADD 3D01R5F-GP..1
R 4
(-2500 2825);
FORCEPROP 0 LAST STATUS NOPOP
J 0
(-2475 2925);
DISPLAY 1.021277 (-2475 2925);
PAINT ORANGE (-2475 2925);
FORCEPROP 1 LAST LOCATION RT38
J 0
(-2450 2845);
DISPLAY 0.617021 (-2450 2845);
PAINT GREEN (-2450 2845);
FORCEPROP 1 LAST VALUE 3D01R5F-GP
J 0
(-2475 2800);
DISPLAY 0.617021 (-2475 2800);
PAINT GREEN (-2475 2800);
FORCEPROP 2 LASTPIN (-2500 2950) SIG_NAME UN$210$3D01R5F-GP$I59$2
J 0
(-2490 2960);
DISPLAY 0.659574 (-2490 2960);
PAINT MONO (-2490 2960);
DISPLAY INVISIBLE (-2490 2960);
FORCEPROP 1 LAST PACK_TYPE SMD-RG5
R 2
J 0
(-2500 2825);
DISPLAY 0.617021 (-2500 2825);
PAINT GREEN (-2500 2825);
DISPLAY INVISIBLE (-2500 2825);
FORCEPROP 1 LAST PART_NUMBER 64.3R015.16L
R 2
J 0
(-2500 2825);
DISPLAY 0.617021 (-2500 2825);
PAINT GREEN (-2500 2825);
DISPLAY INVISIBLE (-2500 2825);
FORCEPROP 2 LAST CDS_LIB w_hdl
J 0
(-2500 2825);
PAINT MONO (-2500 2825);
DISPLAY INVISIBLE (-2500 2825);
FORCEPROP 1 LAST PATH I59
R 2
J 0
(-2500 2825);
DISPLAY 0.617021 (-2500 2825);
PAINT GREEN (-2500 2825);
DISPLAY INVISIBLE (-2500 2825);
FORCEPROP 1 LAST CDS_LMAN_SYM_OUTLINE -50,75,50,-75
R 2
J 0
(-2500 2825);
DISPLAY 0.468085 (-2500 2825);
PAINT GREEN (-2500 2825);
DISPLAY INVISIBLE (-2500 2825);
FORCEADD OFFPAGE..2
(-2125 3800);
FORCEPROP 2 LAST $XR0 206 
J 0
(-1936 3800);
DISPLAY 0.638298 (-1936 3800);
PAINT MONO (-1936 3800);
FORCEPROP 1 LAST OFFPAGE TRUE
J 0
(-1800 3675);
DISPLAY 1.723404 (-1800 3675);
PAINT GREEN (-1800 3675);
DISPLAY INVISIBLE (-1800 3675);
FORCEPROP 2 LAST BOM_COST PROC_VRD_VCCIN_CPU0
J 0
(-1925 3850);
DISPLAY 1.446809 (-1925 3850);
PAINT MONO (-1925 3850);
DISPLAY INVISIBLE (-1925 3850);
FORCEPROP 2 LAST PATH I6
J 0
(-1870 3850);
DISPLAY 1.021277 (-1870 3850);
PAINT ORANGE (-1870 3850);
DISPLAY INVISIBLE (-1870 3850);
FORCEPROP 2 LAST CDS_LIB mstr_standard
J 0
(-2125 3800);
PAINT ORANGE (-2125 3800);
DISPLAY INVISIBLE (-2125 3800);
FORCEPROP 1 LAST COMMENT_BODY TRUE
J 0
(-2170 3705);
DISPLAY 1.723404 (-2170 3705);
PAINT GREEN (-2170 3705);
DISPLAY INVISIBLE (-2170 3705);
FORCEPROP 2 LAST ROOM PVSA_CPU1_PWR_VR
J 0
(-2525 3875);
DISPLAY 1.936170 (-2525 3875);
PAINT ORANGE (-2525 3875);
DISPLAY INVISIBLE (-2525 3875);
FORCEADD CAP..1
(-2650 3625);
FORCEPROP 1 LAST PACK_TYPE 0402LF
J 0
(-2600 3425);
DISPLAY 0.617021 (-2600 3425);
PAINT SKYBLUE (-2600 3425);
FORCEPROP 1 LAST MATERIAL X7R
J 0
(-2600 3525);
DISPLAY 0.617021 (-2600 3525);
PAINT SKYBLUE (-2600 3525);
FORCEPROP 1 LAST PART_NUMBER A36096-046
J 0
(-2600 3475);
DISPLAY 0.617021 (-2600 3475);
PAINT BLUE (-2600 3475);
FORCEPROP 0 LAST STATUS NOPOP
J 0
(-2525 3600);
DISPLAY 1.021277 (-2525 3600);
PAINT ORANGE (-2525 3600);
FORCEPROP 1 LAST VALUE 1000PF
J 0
(-2600 3675);
DISPLAY 0.617021 (-2600 3675);
PAINT SKYBLUE (-2600 3675);
FORCEPROP 1 LAST VOLTAGE 50V
J 0
(-2600 3625);
DISPLAY 0.617021 (-2600 3625);
PAINT SKYBLUE (-2600 3625);
FORCEPROP 1 LAST TOLERANCE 10%
J 0
(-2600 3575);
DISPLAY 0.617021 (-2600 3575);
PAINT SKYBLUE (-2600 3575);
FORCEPROP 1 LAST LOCATION CT55
J 0
(-2600 3725);
DISPLAY 0.617021 (-2600 3725);
PAINT AQUA (-2600 3725);
FORCEPROP 0 LAST ROOM VDDQ_KLM_PWR_VR
J 0
(-2600 3825);
DISPLAY 1.021277 (-2600 3825);
PAINT ORANGE (-2600 3825);
DISPLAY INVISIBLE (-2600 3825);
FORCEPROP 1 LAST PATH I60
J 0
(-2600 3775);
DISPLAY 0.978723 (-2600 3775);
PAINT WHITE (-2600 3775);
DISPLAY INVISIBLE (-2600 3775);
FORCEPROP 2 LAST CDS_LIB mstr_discrete
J 0
(-2650 3625);
PAINT MONO (-2650 3625);
DISPLAY INVISIBLE (-2650 3625);
FORCEPROP 1 LASTPIN (-2650 3525) $PN 2
J 0
(-2640 3505);
DISPLAY 0.787234 (-2640 3505);
PAINT ORANGE (-2640 3505);
DISPLAY INVISIBLE (-2640 3505);
FORCEPROP 1 LASTPIN (-2650 3725) $PN 1
J 0
(-2640 3705);
DISPLAY 0.787234 (-2640 3705);
PAINT ORANGE (-2640 3705);
DISPLAY INVISIBLE (-2640 3705);
FORCEADD GND..1
(-2650 3425);
FORCEPROP 3 LASTPIN (-2650 3475) SIG_NAME GND\g
J 0
(-2640 3485);
DISPLAY 0.659574 (-2640 3485);
PAINT MONO (-2640 3485);
DISPLAY INVISIBLE (-2640 3485);
FORCEPROP 2 LAST CDS_LIB mstr_symbols
J 0
(-2650 3425);
PAINT MONO (-2650 3425);
DISPLAY INVISIBLE (-2650 3425);
FORCEPROP 1 LAST PATH I61
J 0
(-2575 3425);
DISPLAY 0.872340 (-2575 3425);
PAINT AQUA (-2575 3425);
DISPLAY INVISIBLE (-2575 3425);
FORCEPROP 2 LAST ROOM VDDQ_KLM_PWR_VR
J 0
(-3225 3500);
DISPLAY 1.361702 (-3225 3500);
PAINT ORANGE (-3225 3500);
DISPLAY INVISIBLE (-3225 3500);
FORCEPROP 1 LAST VOLTAGE 0
J 0
(-2650 3425);
PAINT SKYBLUE (-2650 3425);
DISPLAY INVISIBLE (-2650 3425);
FORCEPROP 1 LAST BODY_TYPE PLUMBING
J 0
(-2695 3382);
DISPLAY 0.340426 (-2695 3382);
PAINT GREEN (-2695 3382);
DISPLAY INVISIBLE (-2695 3382);
FORCEPROP 1 LAST SIZE 1B
J 0
(-2575 3375);
DISPLAY 1.170213 (-2575 3375);
PAINT AQUA (-2575 3375);
DISPLAY INVISIBLE (-2575 3375);
FORCEPROP 1 LAST HDL_POWER GND
J 0
(-2650 3575);
DISPLAY 1.170213 (-2650 3575);
PAINT GREEN (-2650 3575);
DISPLAY INVISIBLE (-2650 3575);
FORCEADD RES..1
(-5425 3375);
FORCEPROP 1 LAST PACK_TYPE 0402
J 0
(-5325 3225);
DISPLAY 0.617021 (-5325 3225);
PAINT SKYBLUE (-5325 3225);
FORCEPROP 1 LAST PART_NUMBER G21497-005
J 0
(-5525 3325);
DISPLAY 0.617021 (-5525 3325);
PAINT BLUE (-5525 3325);
FORCEPROP 1 LAST LOCATION RT37
J 0
(-5475 3400);
DISPLAY 0.617021 (-5475 3400);
PAINT AQUA (-5475 3400);
FORCEPROP 1 LAST WATTAGE 1/16W
J 2
(-5450 3225);
DISPLAY 0.617021 (-5450 3225);
PAINT SKYBLUE (-5450 3225);
FORCEPROP 1 LAST MATERIAL CHIP
J 0
(-5425 3225);
DISPLAY 0.617021 (-5425 3225);
PAINT SKYBLUE (-5425 3225);
FORCEPROP 1 LAST TOLERANCE 5%
J 0
(-5425 3275);
DISPLAY 0.617021 (-5425 3275);
PAINT SKYBLUE (-5425 3275);
FORCEPROP 1 LAST VALUE 0.0
J 2
(-5450 3275);
DISPLAY 0.617021 (-5450 3275);
PAINT SKYBLUE (-5450 3275);
FORCEPROP 2 LAST BOM_COST DEBUG
J 0
(-5475 3575);
DISPLAY 1.021277 (-5475 3575);
PAINT ORANGE (-5475 3575);
DISPLAY INVISIBLE (-5475 3575);
FORCEPROP 2 LAST ROOM BMC_DEBUG_HEADER
J 0
(-5475 3525);
DISPLAY 1.021277 (-5475 3525);
PAINT ORANGE (-5475 3525);
DISPLAY INVISIBLE (-5475 3525);
FORCEPROP 1 LAST PATH I62
J 0
(-5475 3525);
DISPLAY 0.978723 (-5475 3525);
PAINT WHITE (-5475 3525);
DISPLAY INVISIBLE (-5475 3525);
FORCEPROP 2 LAST CDS_LIB mstr_discrete
J 0
(-5425 3375);
PAINT MONO (-5425 3375);
DISPLAY INVISIBLE (-5425 3375);
FORCEPROP 1 LASTPIN (-5525 3375) $PN 1
J 0
(-5513 3387);
DISPLAY 0.787234 (-5513 3387);
PAINT ORANGE (-5513 3387);
DISPLAY INVISIBLE (-5513 3387);
FORCEPROP 1 LASTPIN (-5325 3375) $PN 2
J 0
(-5363 3387);
DISPLAY 0.787234 (-5363 3387);
PAINT ORANGE (-5363 3387);
DISPLAY INVISIBLE (-5363 3387);
FORCEADD PVSA_CPU1..1
(-625 3475);
FORCEPROP 3 LASTPIN (-625 3425) SIG_NAME PVSA_CPU1\g
J 0
(-615 3435);
DISPLAY 0.659574 (-615 3435);
PAINT MONO (-615 3435);
DISPLAY INVISIBLE (-615 3435);
FORCEPROP 1 LAST HDL_POWER PVSA_CPU1
J 1
(-625 3525);
DISPLAY 0.872340 (-625 3525);
PAINT GREEN (-625 3525);
DISPLAY INVISIBLE (-625 3525);
FORCEPROP 1 LAST BODY_TYPE PLUMBING
J 0
(-670 3432);
DISPLAY 0.340426 (-670 3432);
PAINT GREEN (-670 3432);
DISPLAY INVISIBLE (-670 3432);
FORCEPROP 2 LAST CDS_LIB mstr_symbols
J 0
(-625 3475);
PAINT ORANGE (-625 3475);
DISPLAY INVISIBLE (-625 3475);
FORCEPROP 1 LAST VOLTAGE 1.1V
J 0
(-670 3432);
DISPLAY 0.340426 (-670 3432);
PAINT SKYBLUE (-670 3432);
DISPLAY INVISIBLE (-670 3432);
FORCEPROP 1 LAST PATH I7
J 0
(-575 3500);
DISPLAY 0.872340 (-575 3500);
PAINT AQUA (-575 3500);
DISPLAY INVISIBLE (-575 3500);
FORCEADD CAP_A..1
(-1400 3050);
FORCEPROP 1 LAST LOCATION C1C19
J 0
(-1350 3150);
DISPLAY 0.617021 (-1350 3150);
PAINT AQUA (-1350 3150);
FORCEPROP 1 LAST VALUE 22.0UF
J 0
(-1350 3100);
DISPLAY 0.617021 (-1350 3100);
PAINT SKYBLUE (-1350 3100);
FORCEPROP 1 LASTPIN (-1400 3150) $PN 1
J 0
(-1390 3130);
DISPLAY 0.617021 (-1390 3130);
PAINT ORANGE (-1390 3130);
FORCEPROP 1 LAST VOLTAGE 4V
J 0
(-1350 3050);
DISPLAY 0.617021 (-1350 3050);
PAINT SKYBLUE (-1350 3050);
FORCEPROP 1 LAST PART_NUMBER E15431-004
J 0
(-1350 2900);
DISPLAY 0.617021 (-1350 2900);
PAINT BLUE (-1350 2900);
FORCEPROP 1 LAST TOLERANCE 20%
J 0
(-1350 3000);
DISPLAY 0.617021 (-1350 3000);
PAINT SKYBLUE (-1350 3000);
FORCEPROP 1 LAST PACK_TYPE 0603V
J 0
(-1350 2850);
DISPLAY 0.617021 (-1350 2850);
PAINT SKYBLUE (-1350 2850);
FORCEPROP 1 LAST MATERIAL X6S
J 0
(-1350 2950);
DISPLAY 0.617021 (-1350 2950);
PAINT SKYBLUE (-1350 2950);
FORCEPROP 1 LASTPIN (-1400 2950) $PN 2
J 0
(-1390 2930);
DISPLAY 0.617021 (-1390 2930);
PAINT ORANGE (-1390 2930);
FORCEPROP 1 LAST PATH I8
J 0
(-1350 3200);
DISPLAY 0.978723 (-1350 3200);
PAINT WHITE (-1350 3200);
DISPLAY INVISIBLE (-1350 3200);
FORCEPROP 2 LAST SEC 1
J 0
(-1345 3250);
DISPLAY 0.680851 (-1345 3250);
PAINT MONO (-1345 3250);
DISPLAY INVISIBLE (-1345 3250);
FORCEPROP 2 LAST SEC_TYPE 0603V
J 0
(-1345 3250);
DISPLAY 1.021277 (-1345 3250);
PAINT ORANGE (-1345 3250);
DISPLAY INVISIBLE (-1345 3250);
FORCEPROP 2 LAST CDS_SEC 1
J 0
(-1350 3200);
PAINT ORANGE (-1350 3200);
DISPLAY INVISIBLE (-1350 3200);
FORCEPROP 2 LAST BOM_COST PROC_VRD_VCCIN_CPU0
J 0
(-1350 3200);
DISPLAY 1.446809 (-1350 3200);
PAINT MONO (-1350 3200);
DISPLAY INVISIBLE (-1350 3200);
FORCEPROP 2 LAST ROOM PVSA_CPU1_PWR_VR
J 0
(-1350 3200);
DISPLAY 1.446809 (-1350 3200);
PAINT MONO (-1350 3200);
DISPLAY INVISIBLE (-1350 3200);
FORCEPROP 2 LAST CDS_LOCATION C1C19
J 0
(-1350 3150);
DISPLAY 0.617021 (-1350 3150);
PAINT AQUA (-1350 3150);
DISPLAY INVISIBLE (-1350 3150);
FORCEPROP 2 LAST CDS_LIB dev_discrete
J 0
(-1400 3050);
PAINT ORANGE (-1400 3050);
DISPLAY INVISIBLE (-1400 3050);
FORCEADD GND..1
(-1400 2700);
FORCEPROP 3 LASTPIN (-1400 2750) SIG_NAME GND\g
J 0
(-1390 2760);
DISPLAY 0.659574 (-1390 2760);
PAINT MONO (-1390 2760);
DISPLAY INVISIBLE (-1390 2760);
FORCEPROP 1 LAST HDL_POWER GND
J 0
(-1400 2850);
DISPLAY 1.723404 (-1400 2850);
PAINT GREEN (-1400 2850);
DISPLAY INVISIBLE (-1400 2850);
FORCEPROP 1 LAST BODY_TYPE PLUMBING
J 0
(-1445 2657);
DISPLAY 0.340426 (-1445 2657);
PAINT GREEN (-1445 2657);
DISPLAY INVISIBLE (-1445 2657);
FORCEPROP 1 LAST SIZE 1B
J 0
(-1325 2650);
DISPLAY 1.723404 (-1325 2650);
PAINT GREEN (-1325 2650);
DISPLAY INVISIBLE (-1325 2650);
FORCEPROP 1 LAST PATH I9
J 0
(-1325 2700);
DISPLAY 0.872340 (-1325 2700);
PAINT AQUA (-1325 2700);
DISPLAY INVISIBLE (-1325 2700);
FORCEPROP 1 LAST VOLTAGE 0
J 0
(-1400 2700);
PAINT SKYBLUE (-1400 2700);
DISPLAY INVISIBLE (-1400 2700);
FORCEPROP 2 LAST CDS_LIB mstr_symbols
J 0
(-1400 2700);
PAINT ORANGE (-1400 2700);
DISPLAY INVISIBLE (-1400 2700);
FORCEPROP 2 LAST BOM_COST PROC_VRD_VCCIN_CPU0
J 0
(-1775 2775);
DISPLAY 1.446809 (-1775 2775);
PAINT MONO (-1775 2775);
DISPLAY INVISIBLE (-1775 2775);
FORCEPROP 2 LAST ROOM PVSA_CPU1_PWR_VR
J 0
(-1950 2775);
DISPLAY 1.936170 (-1950 2775);
PAINT ORANGE (-1950 2775);
DISPLAY INVISIBLE (-1950 2775);
FORCEADD DESIGN_NOTE..1
(-3000 1675);
PAINT PURPLE (-3000 1675);
FORCEPROP 2 LAST CDS_LIB mstr_symbols
J 0
(-3000 1675);
PAINT ORANGE (-3000 1675);
DISPLAY INVISIBLE (-3000 1675);
FORCEPROP 1 LAST COMMENT_BODY TRUE
J 0
(-2975 1775);
DISPLAY 1.319149 (-2975 1775);
PAINT GREEN (-2975 1775);
DISPLAY INVISIBLE (-2975 1775);
FORCEPROP 2 LAST BOM_COST SM_CONTROLLER
J 0
(-3200 1625);
PAINT MONO (-3200 1625);
DISPLAY INVISIBLE (-3200 1625);
FORCEPROP 2 LAST ROOM PVCCIN_CPU0_VR
J 0
(-3200 1625);
PAINT MONO (-3200 1625);
DISPLAY INVISIBLE (-3200 1625);
FORCEADD DNS..2
(-5945 1720);
PAINT RED (-5945 1720);
FORCEPROP 2 LAST CDS_LIB mstr_misc
J 0
(-5945 1720);
PAINT ORANGE (-5945 1720);
DISPLAY INVISIBLE (-5945 1720);
FORCEPROP 1 LAST COMMENT_BODY TRUE
R 1
J 0
(-5870 1495);
DISPLAY 0.872340 (-5870 1495);
PAINT GREEN (-5870 1495);
DISPLAY INVISIBLE (-5870 1495);
FORCEADD DNS..2
(-1445 3770);
PAINT RED (-1445 3770);
FORCEPROP 2 LAST CDS_LIB mstr_misc
J 0
(-1445 3770);
PAINT ORANGE (-1445 3770);
DISPLAY INVISIBLE (-1445 3770);
FORCEPROP 1 LAST COMMENT_BODY TRUE
R 1
J 0
(-1370 3545);
DISPLAY 0.872340 (-1370 3545);
PAINT GREEN (-1370 3545);
DISPLAY INVISIBLE (-1370 3545);
FORCEADD INTEL_CORP_BPAGE..1
(0 0);
FORCEPROP 1 LAST CDS_CON_LAST_MODIFIED Tue Dec 01 11:52:23 2015
J 0
(-1425 325);
PAINT ORANGE (-1425 325);
DISPLAY INVISIBLE (-1425 325);
FORCEPROP 1 LAST CUSTOM_TXT_CDS <CURRENT_DESIGN_SHEET> OF <TOTAL_DESIGN_SHEETS>
J 0
(-500 25);
PAINT GREEN (-500 25);
FORCEPROP 1 LAST CUSTOM_TXT_CDS <CON_LAST_MODIFIED>
J 0
(-1925 350);
PAINT GREEN (-1925 350);
FORCEPROP 2 LAST CUSTOM_TXT_CDS <XR_PAGE_TITLE>
J 0
(-7890 5250);
DISPLAY 0.638298 (-7890 5250);
PAINT PINK (-7890 5250);
DISPLAY INVISIBLE (-7890 5250);
FORCEPROP 1 LAST SCH_REV 2.420
J 0
(-250 150);
DISPLAY 0.978723 (-250 150);
PAINT YELLOW (-250 150);
FORCEPROP 1 LAST SCH_DEPT BESD
J 1
(-4450 100);
DISPLAY 1.212766 (-4450 100);
PAINT YELLOW (-4450 100);
FORCEPROP 1 LAST SCH_NUMBER H4694802
J 0
(-1300 150);
DISPLAY 1.212766 (-1300 150);
PAINT YELLOW (-1300 150);
FORCEPROP 1 LAST SCH_ADDRESS3 Santa Clara, CA 95052-8119
J 0
(-3975 25);
DISPLAY 0.617021 (-3975 25);
PAINT GREEN (-3975 25);
FORCEPROP 1 LAST SCH_ADDRESS2 P.O. BOX 58119
J 0
(-3975 75);
DISPLAY 0.617021 (-3975 75);
PAINT GREEN (-3975 75);
FORCEPROP 1 LAST SCH_ADDRESS1 2200 Mission College Blvd.
J 0
(-3975 125);
DISPLAY 0.617021 (-3975 125);
PAINT GREEN (-3975 125);
FORCEPROP 1 LAST SCH_TITLE VSA CPU1
J 0
(-7950 50);
DISPLAY 1.212766 (-7950 50);
PAINT ORANGE (-7950 50);
FORCEPROP 1 LAST COMMENT_BODY TRUE
J 0
(12 12);
DISPLAY 0.468085 (12 12);
PAINT GREEN (12 12);
DISPLAY INVISIBLE (12 12);
FORCEPROP 2 LAST CDS_LIB mstr_symbols
J 0
(0 0);
PAINT MONO (0 0);
DISPLAY INVISIBLE (0 0);
FORCEPROP 2 LAST PAGE_BORDER TRUE
J 0
(-7890 5250);
DISPLAY 0.638298 (-7890 5250);
PAINT PINK (-7890 5250);
DISPLAY INVISIBLE (-7890 5250);
FORCEPROP 2 LAST CDS_XR_PAGE_TITLE CR-210 : @BASEBOARD_FAB2_LIB.BASEBOARD_FAB2(SCH_1):PAGE210
J 0
(-7890 5250);
DISPLAY 0.638298 (-7890 5250);
PAINT PINK (-7890 5250);
DISPLAY INVISIBLE (-7890 5250);
WIRE 16 -1 (-1575 1275)(-1575 1150);
WIRE 16 -1 (-1575 1150)(-1325 1150);
WIRE 16 -1 (-1325 1150)(-1325 1275);
WIRE 16 -1 (-1325 1025)(-1325 1150);
WIRE 16 -1 (-3225 3200)(-3100 3200);
WIRE 16 -1 (-3100 3150)(-3100 3200);
WIRE 16 -1 (-3100 3100)(-3100 3150);
WIRE 16 -1 (-3100 3150)(-3225 3150);
WIRE 16 -1 (-3100 3100)(-3225 3100);
WIRE 16 -1 (-3100 3050)(-3100 3100);
WIRE 16 -1 (-3100 2950)(-3100 3050);
WIRE 16 -1 (-3100 3050)(-3225 3050);
WIRE 16 -1 (-4350 4100)(-4225 4100);
WIRE 16 -1 (-4350 4050)(-4350 4100);
WIRE 16 -1 (-4225 4050)(-4350 4050);
WIRE 16 -1 (-4350 4050)(-6325 4050);
WIRE 16 -1 (-6325 3950)(-6325 4050);
WIRE 16 -1 (-6325 4050)(-6600 4050);
WIRE 16 -1 (-6600 3950)(-6600 4050);
WIRE 16 -1 (-6600 4050)(-6850 4050);
WIRE 16 -1 (-6850 3925)(-6850 4050);
WIRE 16 -1 (-6850 4050)(-7150 4050);
WIRE 16 -1 (-7150 3950)(-7150 4050);
WIRE 16 -1 (-7150 4050)(-7400 4050);
WIRE 16 -1 (-7400 3950)(-7400 4050);
WIRE 16 -1 (-7400 4050)(-7400 4175);
WIRE 16 -1 (-4450 1000)(-4450 1100);
WIRE 16 -1 (-4450 1100)(-5175 1100);
WIRE 16 -1 (-5375 3750)(-5375 3575);
WIRE 16 -1 (-5375 3575)(-5500 3575);
WIRE 16 -1 (-5500 3750)(-5500 3575);
WIRE 16 -1 (-6025 3575)(-5500 3575);
WIRE 16 -1 (-6025 3725)(-6025 3575);
WIRE 16 -1 (-6025 3575)(-6325 3575);
WIRE 16 -1 (-6325 3750)(-6325 3575);
WIRE 16 -1 (-6325 3575)(-6600 3575);
WIRE 16 -1 (-6600 3750)(-6600 3575);
WIRE 16 -1 (-6600 3575)(-6850 3575);
WIRE 16 -1 (-6850 3725)(-6850 3575);
WIRE 16 -1 (-6850 3575)(-7150 3575);
WIRE 16 -1 (-7150 3750)(-7150 3575);
WIRE 16 -1 (-7150 3575)(-7400 3575);
WIRE 16 -1 (-7400 3750)(-7400 3575);
WIRE 16 -1 (-7400 3400)(-7400 3575);
WIRE 16 -1 (-4550 3850)(-4225 3850);
WIRE 16 -1 (-4550 3950)(-4550 3850);
WIRE 16 -1 (-4550 4425)(-4550 3950);
WIRE 16 -1 (-4550 3950)(-4225 3950);
WIRE 16 -1 (-4825 4425)(-4550 4425);
WIRE 16 -1 (-4825 4425)(-5375 4425);
WIRE 16 -1 (-4825 4425)(-4825 4525);
WIRE 16 -1 (-5375 4425)(-5500 4425);
WIRE 16 -1 (-5375 3950)(-5375 4425);
WIRE 16 -1 (-5500 4425)(-5600 4425);
WIRE 16 -1 (-5500 3950)(-5500 4425);
WIRE 16 -1 (-5200 2325)(-4575 2325);
WIRE 16 -1 (-4575 2325)(-4575 2450);
WIRE 16 -1 (-1575 1475)(-1575 1575);
WIRE 16 -1 (-1575 1575)(-1325 1575);
WIRE 16 -1 (-1325 1475)(-1325 1575);
WIRE 16 -1 (-1325 1575)(-1325 1650);
WIRE 16 -1 (-1450 3675)(-1450 3575);
WIRE 16 -1 (-4450 3000)(-4450 2900);
WIRE 16 -1 (-2500 2700)(-2500 2650);
WIRE 16 -1 (-2650 3525)(-2650 3475);
WIRE 16 -1 (-4225 3750)(-4350 3750);
WIRE 16 -1 (-4350 3750)(-4350 2375);
WIRE 16 -1 (-4350 2375)(-1675 2375);
WIRE 16 -1 (-1675 2375)(-1675 3300);
WIRE 16 -1 (-1800 3300)(-1675 3300);
WIRE 16 -1 (-1675 3300)(-1400 3300);
WIRE 16 -1 (-1400 3150)(-1400 3300);
WIRE 16 -1 (-1400 3300)(-1050 3300);
WIRE 16 -1 (-1050 3150)(-1050 3300);
WIRE 16 -1 (-625 3300)(-1050 3300);
WIRE 16 -1 (-625 3175)(-625 3300);
WIRE 16 -1 (-625 3425)(-625 3300);
WIRE 16 -1 (-625 2975)(-625 2825);
WIRE 16 -1 (-625 2825)(-1050 2825);
WIRE 16 -1 (-1050 2950)(-1050 2825);
WIRE 16 -1 (-1400 2825)(-1050 2825);
WIRE 16 -1 (-1400 2825)(-1400 2950);
WIRE 16 -1 (-1400 2750)(-1400 2825);
WIRE 16 -1 (-5175 1925)(-4000 1925);
FORCEPROP 2 LAST SIG_NAME VSENSE_PVSA_CPU1_SKT_VSEN
J 0
(-4945 1945);
DISPLAY 0.617021 (-4945 1945);
PAINT ORANGE (-4945 1945);
WIRE 3 2175 (-2650 3325)(-2175 3325);
WIRE 3 2175 (-2650 3325)(-2650 2550);
WIRE 3 2175 (-2175 3325)(-2175 2550);
WIRE 3 2175 (-2650 2550)(-2175 2550);
WIRE 16 -1 (-2000 3300)(-2500 3300);
WIRE 16 -1 (-2500 3200)(-2500 3300);
WIRE 16 -1 (-2500 3300)(-3225 3300);
FORCEPROP 0 LAST VOLTAGE 5
J 0
(-2825 3375);
DISPLAY 1.021277 (-2825 3375);
PAINT SKYBLUE (-2825 3375);
DISPLAY INVISIBLE (-2825 3375);
FORCEPROP 2 LAST SIG_NAME VR_PVSA_CPU1_PHASE_SW
J 0
(-3110 3310);
DISPLAY 0.617021 (-3110 3310);
PAINT ORANGE (-3110 3310);
FORCEPROP 2 LASTPROP $XRERR UNIQUE?
J 0
(-3350 3310);
DISPLAY 0.638298 (-3350 3310);
PAINT MONO (-3350 3310);
DISPLAY INVISIBLE (-3350 3310);
WIRE 3 2175 (-2750 3850)(-2300 3850);
WIRE 3 2175 (-2750 3850)(-2750 3375);
WIRE 3 2175 (-2300 3850)(-2300 3375);
WIRE 3 2175 (-2750 3375)(-2300 3375);
WIRE 16 -1 (-2650 3725)(-2650 3800);
WIRE 16 -1 (-2650 3800)(-2175 3800);
WIRE 16 -1 (-3150 3800)(-2650 3800);
FORCEPROP 2 LAST SIG_NAME A_TSENSE_PVSA_CPU1
J 0
(-3150 3813);
DISPLAY 0.617021 (-3150 3813);
PAINT ORANGE (-3150 3813);
WIRE 16 -1 (-3150 3800)(-3150 3650);
WIRE 16 -1 (-3150 3650)(-3225 3650);
WIRE 3 2175 (-4725 3350)(-4125 3350);
WIRE 3 2175 (-4725 3350)(-4725 2825);
WIRE 3 2175 (-4125 3350)(-4125 2825);
WIRE 3 2175 (-4725 2825)(-4125 2825);
WIRE 16 -1 (-4225 3400)(-4450 3400);
WIRE 16 -1 (-4450 3400)(-4450 4625);
WIRE 16 -1 (-4450 3200)(-4450 3400);
WIRE 16 -1 (-4450 4625)(-1750 4625);
FORCEPROP 2 LAST SIG_NAME VR_PVSA_CPU1_BIREF1
J 0
(-2605 4642);
DISPLAY 0.617021 (-2605 4642);
PAINT ORANGE (-2605 4642);
WIRE 16 -1 (-5325 3375)(-4550 3375);
FORCEPROP 2 LAST SIG_NAME VR_PVSA_CPU1_BOOT_R
J 0
(-5189 3385);
DISPLAY 0.617021 (-5189 3385);
PAINT ORANGE (-5189 3385);
FORCEPROP 2 LASTPROP $XRERR UNIQUE?
J 0
(-5429 3385);
DISPLAY 0.638298 (-5429 3385);
PAINT MONO (-5429 3385);
DISPLAY INVISIBLE (-5429 3385);
WIRE 16 -1 (-4550 3375)(-4550 3300);
WIRE 16 -1 (-4550 3300)(-4225 3300);
WIRE 16 -1 (-6125 3125)(-4550 3125);
FORCEPROP 0 LAST VOLTAGE 5
J 0
(-5950 3200);
DISPLAY 1.021277 (-5950 3200);
PAINT SKYBLUE (-5950 3200);
DISPLAY INVISIBLE (-5950 3200);
FORCEPROP 2 LAST SIG_NAME VR_PVSA_CPU1_PHASE
J 0
(-6080 3135);
DISPLAY 0.617021 (-6080 3135);
PAINT ORANGE (-6080 3135);
FORCEPROP 2 LASTPROP $XRERR UNIQUE?
J 0
(-6320 3135);
DISPLAY 0.638298 (-6320 3135);
PAINT MONO (-6320 3135);
DISPLAY INVISIBLE (-6320 3135);
WIRE 16 -1 (-6125 3125)(-6125 3150);
WIRE 16 -1 (-4550 3125)(-4550 3250);
WIRE 16 -1 (-4550 3250)(-4225 3250);
WIRE 3 2175 (-5600 3175)(-5225 3175);
WIRE 3 2175 (-5600 3475)(-5600 3175);
WIRE 3 2175 (-5225 3475)(-5225 3175);
WIRE 3 2175 (-5600 3475)(-5225 3475);
WIRE 16 -1 (-5525 3375)(-6125 3375);
FORCEPROP 2 LAST SIG_NAME VR_PVSA_CPU1_BOOT
J 0
(-6114 3385);
DISPLAY 0.617021 (-6114 3385);
PAINT ORANGE (-6114 3385);
FORCEPROP 2 LASTPROP $XRERR UNIQUE?
J 0
(-6354 3385);
DISPLAY 0.638298 (-6354 3385);
PAINT MONO (-6354 3385);
DISPLAY INVISIBLE (-6354 3385);
WIRE 16 -1 (-6125 3375)(-6125 3350);
WIRE 16 2175 (-6425 3025)(-5675 3025);
WIRE 16 2175 (-6425 3450)(-6425 3025);
WIRE 16 2175 (-5675 3450)(-5675 3025);
WIRE 16 2175 (-6425 3450)(-5675 3450);
WIRE 16 -1 (-7050 3500)(-4225 3500);
FORCEPROP 2 LAST SIG_NAME VR_PVSA_CPU1_PWM
J 0
(-6983 3510);
DISPLAY 0.617021 (-6983 3510);
PAINT ORANGE (-6983 3510);
WIRE 16 -1 (-7350 1975)(-6500 1975);
FORCEPROP 2 LAST SIG_NAME VSENSE_PVSA_CPU1_P
J 0
(-7320 1995);
DISPLAY 0.617021 (-7320 1995);
PAINT ORANGE (-7320 1995);
WIRE 16 -1 (-6500 1775)(-6500 1975);
WIRE 16 -1 (-6500 1775)(-6175 1775);
WIRE 16 -1 (-6175 1775)(-6175 1925);
WIRE 16 -1 (-6175 1925)(-5950 1925);
WIRE 16 -1 (-5950 1925)(-5600 1925);
WIRE 16 -1 (-5950 1825)(-5950 1925);
WIRE 16 -1 (-5600 2325)(-5600 1925);
WIRE 16 -1 (-5600 1925)(-5375 1925);
WIRE 16 -1 (-5400 2325)(-5600 2325);
WIRE 16 -1 (-7375 1500)(-6500 1500);
FORCEPROP 2 LAST SIG_NAME VSENSE_PVSA_CPU1_N
J 0
(-7370 1520);
DISPLAY 0.617021 (-7370 1520);
PAINT ORANGE (-7370 1520);
WIRE 16 -1 (-6500 1500)(-6500 1700);
WIRE 16 -1 (-6500 1700)(-6175 1700);
WIRE 16 -1 (-6175 1700)(-6175 1475);
WIRE 16 -1 (-6175 1475)(-5950 1475);
WIRE 16 -1 (-5950 1475)(-5600 1475);
WIRE 16 -1 (-5950 1625)(-5950 1475);
WIRE 16 -1 (-5600 1475)(-5375 1475);
WIRE 16 -1 (-5600 1100)(-5600 1475);
WIRE 16 -1 (-5600 1100)(-5375 1100);
WIRE 16 682 (-2375 1750)(-2375 1025);
WIRE 16 682 (-3225 1750)(-2375 1750);
WIRE 16 682 (-2375 1025)(-3225 1025);
WIRE 16 682 (-3225 1025)(-3225 1750);
WIRE 16 -1 (-3225 3950)(-1450 3950);
FORCEPROP 0 LAST SIG_NAME VR_PVSA_CPU1_OCSET
J 0
(-3085 3960);
DISPLAY 0.617021 (-3085 3960);
PAINT ORANGE (-3085 3960);
FORCEPROP 2 LASTPROP $XRERR UNIQUE?
J 0
(-3325 3960);
DISPLAY 0.638298 (-3325 3960);
PAINT MONO (-3325 3960);
DISPLAY INVISIBLE (-3325 3960);
WIRE 16 -1 (-1450 3950)(-1450 3875);
WIRE 16 -1 (-5175 1475)(-4000 1475);
FORCEPROP 2 LAST SIG_NAME VSENSE_PVSA_CPU1_SKT_VRTN
J 0
(-4945 1495);
DISPLAY 0.617021 (-4945 1495);
PAINT ORANGE (-4945 1495);
WIRE 16 -1 (-2500 2950)(-2500 3050);
WIRE 16 2175 (-5750 4025)(-5075 4025);
WIRE 16 2175 (-5750 4025)(-5750 3600);
WIRE 16 2175 (-5075 4025)(-5075 3600);
WIRE 16 2175 (-5750 3600)(-5075 3600);
WIRE 16 -1 (-1525 4150)(-3225 4150);
FORCEPROP 2 LAST SIG_NAME ISENSE_PVSA_CPU1_IMON
J 0
(-2879 4167);
DISPLAY 0.617021 (-2879 4167);
PAINT ORANGE (-2879 4167);
WIRE 16 -1 (-3225 3900)(-2500 3900);
FORCEPROP 2 LAST SIG_NAME NC_PVSA_CPU1_P31
J 0
(-3082 3914);
DISPLAY 0.617021 (-3082 3914);
PAINT ORANGE (-3082 3914);
FORCEPROP 2 LASTPROP $XRERR UNIQUE?
J 0
(-2470 3900);
DISPLAY 0.638298 (-2470 3900);
PAINT MONO (-2470 3900);
DISPLAY INVISIBLE (-2470 3900);
WIRE 16 -1 (-6025 4150)(-4225 4150);
FORCEPROP 0 LAST VOLTAGE 5
J 0
(-5400 4225);
DISPLAY 1.021277 (-5400 4225);
PAINT SKYBLUE (-5400 4225);
DISPLAY INVISIBLE (-5400 4225);
FORCEPROP 2 LAST SIG_NAME VR_PVSA_CPU1_VCIN
J 0
(-5985 4160);
DISPLAY 0.617021 (-5985 4160);
PAINT ORANGE (-5985 4160);
FORCEPROP 2 LASTPROP $XRERR UNIQUE?
J 0
(-6225 4160);
DISPLAY 0.638298 (-6225 4160);
PAINT MONO (-6225 4160);
DISPLAY INVISIBLE (-6225 4160);
WIRE 16 -1 (-6025 4425)(-6025 4150);
WIRE 16 -1 (-6025 3925)(-6025 4150);
WIRE 16 -1 (-6025 4425)(-5800 4425);
WIRE 16 -1 (-4225 3650)(-5000 3650);
FORCEPROP 0 LAST SIG_NAME TP_PVSA_CPU1_GL_1
J 0
(-4985 3660);
DISPLAY 0.617021 (-4985 3660);
PAINT ORANGE (-4985 3660);
FORCEPROP 2 LASTPROP $XRERR UNIQUE?
J 0
(-5240 3650);
DISPLAY 0.638298 (-5240 3650);
PAINT MONO (-5240 3650);
DISPLAY INVISIBLE (-5240 3650);
WIRE 16 -1 (-4225 3600)(-5000 3600);
FORCEPROP 0 LAST SIG_NAME TP_PVSA_CPU1_GL_0
J 0
(-4985 3610);
DISPLAY 0.617021 (-4985 3610);
PAINT ORANGE (-4985 3610);
FORCEPROP 2 LASTPROP $XRERR UNIQUE?
J 0
(-5240 3600);
DISPLAY 0.638298 (-5240 3600);
PAINT MONO (-5240 3600);
DISPLAY INVISIBLE (-5240 3600);
DOT 1 (-2500 3300);
DOT 1 (-4450 3400);
DOT 1 (-7400 3575);
DOT 1 (-7400 4050);
DOT 1 (-7150 3575);
DOT 1 (-6850 3575);
DOT 1 (-7150 4050);
DOT 1 (-6850 4050);
DOT 1 (-6600 4050);
DOT 1 (-6325 4050);
DOT 1 (-5950 1475);
DOT 1 (-5950 1925);
DOT 1 (-5600 1475);
DOT 1 (-5600 1925);
DOT 1 (-6025 3575);
DOT 1 (-5500 3575);
DOT 1 (-4550 3950);
DOT 1 (-4350 4050);
DOT 1 (-6025 4150);
DOT 1 (-5500 4425);
DOT 1 (-5375 4425);
DOT 1 (-4825 4425);
DOT 1 (-3100 3150);
DOT 1 (-1325 1150);
DOT 1 (-1325 1575);
DOT 1 (-1400 2825);
DOT 1 (-1050 2825);
DOT 1 (-1400 3300);
DOT 1 (-1050 3300);
DOT 1 (-625 3300);
DOT 1 (-2650 3800);
DOT 1 (-3100 3100);
DOT 1 (-6325 3575);
DOT 1 (-6600 3575);
DOT 1 (-3100 3050);
DOT 1 (-1675 3300);
FORCENOTE
PLACE ON TOP
(-5755 3525) 0;
DISPLAY LEFT (-5755 3525);
DISPLAY 1.553191 (-5755 3525);
PAINT PURPLE (-5755 3525);
FORCENOTE
SOCKET SIDE
(-4465 1740) 0;
DISPLAY LEFT (-4465 1740);
PAINT PURPLE (-4465 1740);
FORCENOTE
10MIL WIDTH
(-6440 1640) 0;
DISPLAY LEFT (-6440 1640);
DISPLAY 0.808511 (-6440 1640);
PAINT PURPLE (-6440 1640);
FORCENOTE
5MIL SPACING
(-6465 1565) 0;
DISPLAY LEFT (-6465 1565);
DISPLAY 0.808511 (-6465 1565);
PAINT PURPLE (-6465 1565);
FORCENOTE
ROOM = PVSA_CPU1_VSENSE_VR
(-7065 715) 0;
DISPLAY LEFT (-7065 715);
DISPLAY 2.446809 (-7065 715);
PAINT PURPLE (-7065 715);
FORCENOTE
VBOOT=0.9V
(-3200 1075) 0;
DISPLAY LEFT (-3200 1075);
DISPLAY 0.808511 (-3200 1075);
PAINT PURPLE (-3200 1075);
FORCENOTE
IOUT PK=13A
(-3200 1275) 0;
DISPLAY LEFT (-3200 1275);
DISPLAY 0.808511 (-3200 1275);
PAINT PURPLE (-3200 1275);
FORCENOTE
IOUT TDC=12A
(-3200 1325) 0;
DISPLAY LEFT (-3200 1325);
DISPLAY 0.808511 (-3200 1325);
PAINT PURPLE (-3200 1325);
FORCENOTE
SW FREQ=520 KHZ
(-3200 1125) 0;
DISPLAY LEFT (-3200 1125);
DISPLAY 0.808511 (-3200 1125);
PAINT PURPLE (-3200 1125);
FORCENOTE
IOUT DI/DT =20A/US
(-3200 1175) 0;
DISPLAY LEFT (-3200 1175);
DISPLAY 0.808511 (-3200 1175);
PAINT PURPLE (-3200 1175);
FORCENOTE
IOUT STEP=5A/US
(-3200 1225) 0;
DISPLAY LEFT (-3200 1225);
DISPLAY 0.808511 (-3200 1225);
PAINT PURPLE (-3200 1225);
FORCENOTE
RIPPLE = +/- 10MV
(-3200 1475) 0;
DISPLAY LEFT (-3200 1475);
DISPLAY 0.808511 (-3200 1475);
PAINT PURPLE (-3200 1475);
FORCENOTE
VOUT=0.85V (TYP) SVID
(-3200 1525) 0;
DISPLAY LEFT (-3200 1525);
DISPLAY 0.808511 (-3200 1525);
PAINT PURPLE (-3200 1525);
FORCENOTE
DC TOL = +/-5MV
(-3200 1425) 0;
DISPLAY LEFT (-3200 1425);
DISPLAY 0.808511 (-3200 1425);
PAINT PURPLE (-3200 1425);
FORCENOTE
TOTAL TOL = 0.917MAX/0.779VMIN 
(-3200 1375) 0;
DISPLAY LEFT (-3200 1375);
DISPLAY 0.808511 (-3200 1375);
PAINT PURPLE (-3200 1375);
FORCENOTE
ROOM = PVSA_CPU1_DECAP_VR
(-3240 615) 0;
DISPLAY LEFT (-3240 615);
DISPLAY 2.446809 (-3240 615);
PAINT PURPLE (-3240 615);
FORCENOTE
SPOF
(-6130 2925) 0;
DISPLAY LEFT (-6130 2925);
DISPLAY 1.808511 (-6130 2925);
PAINT PURPLE (-6130 2925);
FORCENOTE
VR CONTROLLER SIDE
(-7590 1740) 0;
DISPLAY LEFT (-7590 1740);
PAINT PURPLE (-7590 1740);
FORCENOTE
PVSA CPU0 VOLTAGE SENSE
(-7190 1365) 0;
DISPLAY LEFT (-7190 1365);
PAINT PURPLE (-7190 1365);
FORCENOTE
ROUT AS DIFF PAIR
(-6565 1715) 0;
DISPLAY LEFT (-6565 1715);
DISPLAY 0.808511 (-6565 1715);
PAINT PURPLE (-6565 1715);
FORCENOTE
TP FAB1 3.01 OHM NEED CHANGE TO 2.2 OHM BUT WAIT FOR SYMBOL
(-2175 2600) 0;
DISPLAY LEFT (-2175 2600);
DISPLAY 0.851064 (-2175 2600);
PAINT RED (-2175 2600);
FORCENOTE
TP FAB1 CO-LAY WITH TI PARTS 11/16
(-5675 2875) 0;
DISPLAY LEFT (-5675 2875);
DISPLAY 0.851064 (-5675 2875);
PAINT RED (-5675 2875);
FORCENOTE
ROOM=PVSA_CPU1_PWR_VR
(-3180 1935) 0;
DISPLAY LEFT (-3180 1935);
DISPLAY 2.446809 (-3180 1935);
PAINT PURPLE (-3180 1935);
FORCENOTE
TP FAB1 CO-LAY WITH TI PARTS 11/16
(-2175 2650) 0;
DISPLAY LEFT (-2175 2650);
DISPLAY 0.851064 (-2175 2650);
PAINT RED (-2175 2650);
FORCENOTE
TP FAB1 CO-LAY WITH TI PARTS 11/16
(-2275 3450) 0;
DISPLAY LEFT (-2275 3450);
DISPLAY 0.851064 (-2275 3450);
PAINT RED (-2275 3450);
QUIT
